FILE_TYPE = MACRO_DRAWING;
SET COLOR_WIRE YELLOW;
SET COLOR_PROP ORANGE;
SET COLOR_DOT WHITE;
SET COLOR_ARC YELLOW;
SET COLOR_BODY GREEN;
SET COLOR_NOTE PURPLE;
SET PROP_DISPLAY VALUE;
SET PAGE_NUMBER P30;
FORCEADD GENOA_SP5..27
(-2475 3550);
FORCEPROP 1 LAST LOCATION U25
J 0
(-2975 6700);
DISPLAY 0.489362 (-2975 6700);
PAINT SKYBLUE (-2975 6700);
FORCEPROP 0 LAST $SEC 27
J 0
(-2950 6975);
DISPLAY 0.680851 (-2950 6975);
PAINT MONO (-2950 6975);
DISPLAY INVISIBLE (-2950 6975);
FORCEPROP 0 LAST CDS_SEC 27
J 0
(-1700 6650);
DISPLAY 1.021277 (-1700 6650);
DISPLAY INVISIBLE (-1700 6650);
FORCEPROP 0 LASTPIN (-3125 6525) $PN BJ18
J 2
(-3135 6535);
DISPLAY 0.489362 (-3135 6535);
PAINT MONO (-3135 6535);
FORCEPROP 0 LASTPIN (-3125 6475) $PN BJ23
J 2
(-3135 6485);
DISPLAY 0.489362 (-3135 6485);
PAINT MONO (-3135 6485);
FORCEPROP 0 LASTPIN (-3125 6425) $PN BJ25
J 2
(-3135 6435);
DISPLAY 0.489362 (-3135 6435);
PAINT MONO (-3135 6435);
FORCEPROP 0 LASTPIN (-3125 6375) $PN BJ27
J 2
(-3135 6385);
DISPLAY 0.489362 (-3135 6385);
PAINT MONO (-3135 6385);
FORCEPROP 0 LASTPIN (-3125 6325) $PN BK22
J 2
(-3135 6335);
DISPLAY 0.489362 (-3135 6335);
PAINT MONO (-3135 6335);
FORCEPROP 0 LASTPIN (-3125 6275) $PN BK24
J 2
(-3135 6285);
DISPLAY 0.489362 (-3135 6285);
PAINT MONO (-3135 6285);
FORCEPROP 0 LASTPIN (-3125 6225) $PN BK26
J 2
(-3135 6235);
DISPLAY 0.489362 (-3135 6235);
PAINT MONO (-3135 6235);
FORCEPROP 0 LASTPIN (-3125 6175) $PN BK28
J 2
(-3135 6185);
DISPLAY 0.489362 (-3135 6185);
PAINT MONO (-3135 6185);
FORCEPROP 0 LASTPIN (-3125 6125) $PN BK49
J 2
(-3135 6135);
DISPLAY 0.489362 (-3135 6135);
PAINT MONO (-3135 6135);
FORCEPROP 0 LASTPIN (-3125 6075) $PN BL23
J 2
(-3135 6085);
DISPLAY 0.489362 (-3135 6085);
PAINT MONO (-3135 6085);
FORCEPROP 0 LASTPIN (-3125 6025) $PN BL25
J 2
(-3135 6035);
DISPLAY 0.489362 (-3135 6035);
PAINT MONO (-3135 6035);
FORCEPROP 0 LASTPIN (-3125 5975) $PN BL27
J 2
(-3135 5985);
DISPLAY 0.489362 (-3135 5985);
PAINT MONO (-3135 5985);
FORCEPROP 0 LASTPIN (-3125 5925) $PN BL48
J 2
(-3135 5935);
DISPLAY 0.489362 (-3135 5935);
PAINT MONO (-3135 5935);
FORCEPROP 0 LASTPIN (-3125 5875) $PN BM12
J 2
(-3135 5885);
DISPLAY 0.489362 (-3135 5885);
PAINT MONO (-3135 5885);
FORCEPROP 0 LASTPIN (-3125 5825) $PN BM19
J 2
(-3135 5835);
DISPLAY 0.489362 (-3135 5835);
PAINT MONO (-3135 5835);
FORCEPROP 0 LASTPIN (-3125 5775) $PN BM22
J 2
(-3135 5785);
DISPLAY 0.489362 (-3135 5785);
PAINT MONO (-3135 5785);
FORCEPROP 0 LASTPIN (-3125 5725) $PN BM24
J 2
(-3135 5735);
DISPLAY 0.489362 (-3135 5735);
PAINT MONO (-3135 5735);
FORCEPROP 0 LASTPIN (-3125 5675) $PN BM26
J 2
(-3135 5685);
DISPLAY 0.489362 (-3135 5685);
PAINT MONO (-3135 5685);
FORCEPROP 0 LASTPIN (-3125 5625) $PN BM28
J 2
(-3135 5635);
DISPLAY 0.489362 (-3135 5635);
PAINT MONO (-3135 5635);
FORCEPROP 0 LASTPIN (-3125 5575) $PN BM30
J 2
(-3135 5585);
DISPLAY 0.489362 (-3135 5585);
PAINT MONO (-3135 5585);
FORCEPROP 0 LASTPIN (-3125 5525) $PN BM32
J 2
(-3135 5535);
DISPLAY 0.489362 (-3135 5535);
PAINT MONO (-3135 5535);
FORCEPROP 0 LASTPIN (-3125 5475) $PN BM34
J 2
(-3135 5485);
DISPLAY 0.489362 (-3135 5485);
PAINT MONO (-3135 5485);
FORCEPROP 0 LASTPIN (-3125 5425) $PN BM36
J 2
(-3135 5435);
DISPLAY 0.489362 (-3135 5435);
PAINT MONO (-3135 5435);
FORCEPROP 0 LASTPIN (-3125 5375) $PN BM39
J 2
(-3135 5385);
DISPLAY 0.489362 (-3135 5385);
PAINT MONO (-3135 5385);
FORCEPROP 0 LASTPIN (-3125 5325) $PN BM41
J 2
(-3135 5335);
DISPLAY 0.489362 (-3135 5335);
PAINT MONO (-3135 5335);
FORCEPROP 0 LASTPIN (-3125 5275) $PN BM43
J 2
(-3135 5285);
DISPLAY 0.489362 (-3135 5285);
PAINT MONO (-3135 5285);
FORCEPROP 0 LASTPIN (-3125 5225) $PN BM45
J 2
(-3135 5235);
DISPLAY 0.489362 (-3135 5235);
PAINT MONO (-3135 5235);
FORCEPROP 0 LASTPIN (-3125 5175) $PN BM47
J 2
(-3135 5185);
DISPLAY 0.489362 (-3135 5185);
PAINT MONO (-3135 5185);
FORCEPROP 0 LASTPIN (-3125 5125) $PN BM49
J 2
(-3135 5135);
DISPLAY 0.489362 (-3135 5135);
PAINT MONO (-3135 5135);
FORCEPROP 0 LASTPIN (-3125 5075) $PN BN25
J 2
(-3135 5085);
DISPLAY 0.489362 (-3135 5085);
PAINT MONO (-3135 5085);
FORCEPROP 0 LASTPIN (-3125 5025) $PN BN29
J 2
(-3135 5035);
DISPLAY 0.489362 (-3135 5035);
PAINT MONO (-3135 5035);
FORCEPROP 0 LASTPIN (-3125 4975) $PN BN33
J 2
(-3135 4985);
DISPLAY 0.489362 (-3135 4985);
PAINT MONO (-3135 4985);
FORCEPROP 0 LASTPIN (-3125 4925) $PN BN40
J 2
(-3135 4935);
DISPLAY 0.489362 (-3135 4935);
PAINT MONO (-3135 4935);
FORCEPROP 0 LASTPIN (-3125 4875) $PN BN44
J 2
(-3135 4885);
DISPLAY 0.489362 (-3135 4885);
PAINT MONO (-3135 4885);
FORCEPROP 0 LASTPIN (-3125 4825) $PN BN48
J 2
(-3135 4835);
DISPLAY 0.489362 (-3135 4835);
PAINT MONO (-3135 4835);
FORCEPROP 0 LASTPIN (-3125 4775) $PN BP22
J 2
(-3135 4785);
DISPLAY 0.489362 (-3135 4785);
PAINT MONO (-3135 4785);
FORCEPROP 0 LASTPIN (-3125 4725) $PN BR4
J 2
(-3135 4735);
DISPLAY 0.489362 (-3135 4735);
PAINT MONO (-3135 4735);
FORCEPROP 0 LASTPIN (-3125 4675) $PN BR11
J 2
(-3135 4685);
DISPLAY 0.489362 (-3135 4685);
PAINT MONO (-3135 4685);
FORCEPROP 0 LASTPIN (-3125 4625) $PN BR18
J 2
(-3135 4635);
DISPLAY 0.489362 (-3135 4635);
PAINT MONO (-3135 4635);
FORCEPROP 0 LASTPIN (-3125 4575) $PN BV5
J 2
(-3135 4585);
DISPLAY 0.489362 (-3135 4585);
PAINT MONO (-3135 4585);
FORCEPROP 0 LASTPIN (-3125 4525) $PN BV12
J 2
(-3135 4535);
DISPLAY 0.489362 (-3135 4535);
PAINT MONO (-3135 4535);
FORCEPROP 0 LASTPIN (-3125 4475) $PN BV19
J 2
(-3135 4485);
DISPLAY 0.489362 (-3135 4485);
PAINT MONO (-3135 4485);
FORCEPROP 0 LASTPIN (-3125 4425) $PN BV22
J 2
(-3135 4435);
DISPLAY 0.489362 (-3135 4435);
PAINT MONO (-3135 4435);
FORCEPROP 0 LASTPIN (-3125 4375) $PN CA4
J 2
(-3135 4385);
DISPLAY 0.489362 (-3135 4385);
PAINT MONO (-3135 4385);
FORCEPROP 0 LASTPIN (-3125 4325) $PN CA11
J 2
(-3135 4335);
DISPLAY 0.489362 (-3135 4335);
PAINT MONO (-3135 4335);
FORCEPROP 0 LASTPIN (-3125 4275) $PN CA18
J 2
(-3135 4285);
DISPLAY 0.489362 (-3135 4285);
PAINT MONO (-3135 4285);
FORCEPROP 0 LASTPIN (-3125 4225) $PN CB22
J 2
(-3135 4235);
DISPLAY 0.489362 (-3135 4235);
PAINT MONO (-3135 4235);
FORCEPROP 0 LASTPIN (-3125 4175) $PN CD5
J 2
(-3135 4185);
DISPLAY 0.489362 (-3135 4185);
PAINT MONO (-3135 4185);
FORCEPROP 0 LASTPIN (-3125 4125) $PN CD12
J 2
(-3135 4135);
DISPLAY 0.489362 (-3135 4135);
PAINT MONO (-3135 4135);
FORCEPROP 0 LASTPIN (-3125 4075) $PN CD19
J 2
(-3135 4085);
DISPLAY 0.489362 (-3135 4085);
PAINT MONO (-3135 4085);
FORCEPROP 0 LASTPIN (-3125 4025) $PN CF22
J 2
(-3135 4035);
DISPLAY 0.489362 (-3135 4035);
PAINT MONO (-3135 4035);
FORCEPROP 0 LASTPIN (-3125 3975) $PN CG4
J 2
(-3135 3985);
DISPLAY 0.489362 (-3135 3985);
PAINT MONO (-3135 3985);
FORCEPROP 0 LASTPIN (-3125 3925) $PN CG11
J 2
(-3135 3935);
DISPLAY 0.489362 (-3135 3935);
PAINT MONO (-3135 3935);
FORCEPROP 0 LASTPIN (-3125 3875) $PN CG18
J 2
(-3135 3885);
DISPLAY 0.489362 (-3135 3885);
PAINT MONO (-3135 3885);
FORCEPROP 0 LASTPIN (-3125 3825) $PN CJ22
J 2
(-3135 3835);
DISPLAY 0.489362 (-3135 3835);
PAINT MONO (-3135 3835);
FORCEPROP 0 LASTPIN (-3125 3775) $PN CK5
J 2
(-3135 3785);
DISPLAY 0.489362 (-3135 3785);
PAINT MONO (-3135 3785);
FORCEPROP 0 LASTPIN (-3125 3725) $PN CK12
J 2
(-3135 3735);
DISPLAY 0.489362 (-3135 3735);
PAINT MONO (-3135 3735);
FORCEPROP 0 LASTPIN (-3125 3675) $PN CK19
J 2
(-3135 3685);
DISPLAY 0.489362 (-3135 3685);
PAINT MONO (-3135 3685);
FORCEPROP 0 LASTPIN (-3125 3625) $PN CM22
J 2
(-3135 3635);
DISPLAY 0.489362 (-3135 3635);
PAINT MONO (-3135 3635);
FORCEPROP 0 LASTPIN (-3125 3575) $PN CN4
J 2
(-3135 3585);
DISPLAY 0.489362 (-3135 3585);
PAINT MONO (-3135 3585);
FORCEPROP 0 LASTPIN (-3125 3525) $PN CN11
J 2
(-3135 3535);
DISPLAY 0.489362 (-3135 3535);
PAINT MONO (-3135 3535);
FORCEPROP 0 LASTPIN (-3125 3475) $PN CN18
J 2
(-3135 3485);
DISPLAY 0.489362 (-3135 3485);
PAINT MONO (-3135 3485);
FORCEPROP 0 LASTPIN (-3125 3425) $PN CT5
J 2
(-3135 3435);
DISPLAY 0.489362 (-3135 3435);
PAINT MONO (-3135 3435);
FORCEPROP 0 LASTPIN (-3125 3375) $PN CT12
J 2
(-3135 3385);
DISPLAY 0.489362 (-3135 3385);
PAINT MONO (-3135 3385);
FORCEPROP 0 LASTPIN (-3125 3325) $PN CT19
J 2
(-3135 3335);
DISPLAY 0.489362 (-3135 3335);
PAINT MONO (-3135 3335);
FORCEPROP 0 LASTPIN (-3125 3275) $PN CT22
J 2
(-3135 3285);
DISPLAY 0.489362 (-3135 3285);
PAINT MONO (-3135 3285);
FORCEPROP 0 LASTPIN (-3125 3225) $PN CW4
J 2
(-3135 3235);
DISPLAY 0.489362 (-3135 3235);
PAINT MONO (-3135 3235);
FORCEPROP 0 LASTPIN (-3125 3175) $PN CW11
J 2
(-3135 3185);
DISPLAY 0.489362 (-3135 3185);
PAINT MONO (-3135 3185);
FORCEPROP 0 LASTPIN (-3125 3125) $PN CW18
J 2
(-3135 3135);
DISPLAY 0.489362 (-3135 3135);
PAINT MONO (-3135 3135);
FORCEPROP 0 LASTPIN (-3125 3075) $PN CY22
J 2
(-3135 3085);
DISPLAY 0.489362 (-3135 3085);
PAINT MONO (-3135 3085);
FORCEPROP 0 LASTPIN (-3125 3025) $PN DB5
J 2
(-3135 3035);
DISPLAY 0.489362 (-3135 3035);
PAINT MONO (-3135 3035);
FORCEPROP 0 LASTPIN (-3125 2975) $PN DB12
J 2
(-3135 2985);
DISPLAY 0.489362 (-3135 2985);
PAINT MONO (-3135 2985);
FORCEPROP 0 LASTPIN (-3125 2925) $PN DB19
J 2
(-3135 2935);
DISPLAY 0.489362 (-3135 2935);
PAINT MONO (-3135 2935);
FORCEPROP 0 LASTPIN (-3125 2875) $PN DE4
J 2
(-3135 2885);
DISPLAY 0.489362 (-3135 2885);
PAINT MONO (-3135 2885);
FORCEPROP 0 LASTPIN (-3125 2825) $PN DE11
J 2
(-3135 2835);
DISPLAY 0.489362 (-3135 2835);
PAINT MONO (-3135 2835);
FORCEPROP 0 LASTPIN (-3125 2775) $PN DE18
J 2
(-3135 2785);
DISPLAY 0.489362 (-3135 2785);
PAINT MONO (-3135 2785);
FORCEPROP 0 LASTPIN (-3125 2725) $PN DG5
J 2
(-3135 2735);
DISPLAY 0.489362 (-3135 2735);
PAINT MONO (-3135 2735);
FORCEPROP 0 LASTPIN (-3125 2525) $PN AR52
J 2
(-3135 2535);
DISPLAY 0.489362 (-3135 2535);
PAINT MONO (-3135 2535);
FORCEPROP 0 LASTPIN (-3125 2475) $PN AR54
J 2
(-3135 2485);
DISPLAY 0.489362 (-3135 2485);
PAINT MONO (-3135 2485);
FORCEPROP 0 LASTPIN (-3125 2425) $PN AT51
J 2
(-3135 2435);
DISPLAY 0.489362 (-3135 2435);
PAINT MONO (-3135 2435);
FORCEPROP 0 LASTPIN (-3125 2375) $PN AT53
J 2
(-3135 2385);
DISPLAY 0.489362 (-3135 2385);
PAINT MONO (-3135 2385);
FORCEPROP 0 LASTPIN (-3125 2325) $PN AU50
J 2
(-3135 2335);
DISPLAY 0.489362 (-3135 2335);
PAINT MONO (-3135 2335);
FORCEPROP 0 LASTPIN (-3125 2275) $PN AU52
J 2
(-3135 2285);
DISPLAY 0.489362 (-3135 2285);
PAINT MONO (-3135 2285);
FORCEPROP 0 LASTPIN (-3125 1175) $PN AU54
J 2
(-3135 1185);
DISPLAY 0.489362 (-3135 1185);
PAINT MONO (-3135 1185);
FORCEPROP 0 LASTPIN (-3125 2225) $PN AV49
J 2
(-3135 2235);
DISPLAY 0.489362 (-3135 2235);
PAINT MONO (-3135 2235);
FORCEPROP 0 LASTPIN (-3125 2175) $PN AV51
J 2
(-3135 2185);
DISPLAY 0.489362 (-3135 2185);
PAINT MONO (-3135 2185);
FORCEPROP 0 LASTPIN (-3125 2125) $PN AV53
J 2
(-3135 2135);
DISPLAY 0.489362 (-3135 2135);
PAINT MONO (-3135 2135);
FORCEPROP 0 LASTPIN (-3125 2075) $PN AW50
J 2
(-3135 2085);
DISPLAY 0.489362 (-3135 2085);
PAINT MONO (-3135 2085);
FORCEPROP 0 LASTPIN (-3125 2025) $PN AW52
J 2
(-3135 2035);
DISPLAY 0.489362 (-3135 2035);
PAINT MONO (-3135 2035);
FORCEPROP 0 LASTPIN (-3125 1975) $PN AW54
J 2
(-3135 1985);
DISPLAY 0.489362 (-3135 1985);
PAINT MONO (-3135 1985);
FORCEPROP 0 LASTPIN (-3125 1925) $PN AY51
J 2
(-3135 1935);
DISPLAY 0.489362 (-3135 1935);
PAINT MONO (-3135 1935);
FORCEPROP 0 LASTPIN (-3125 1875) $PN AY53
J 2
(-3135 1885);
DISPLAY 0.489362 (-3135 1885);
PAINT MONO (-3135 1885);
FORCEPROP 0 LASTPIN (-3125 1825) $PN BA50
J 2
(-3135 1835);
DISPLAY 0.489362 (-3135 1835);
PAINT MONO (-3135 1835);
FORCEPROP 0 LASTPIN (-3125 1775) $PN BA52
J 2
(-3135 1785);
DISPLAY 0.489362 (-3135 1785);
PAINT MONO (-3135 1785);
FORCEPROP 0 LASTPIN (-3125 1725) $PN BA54
J 2
(-3135 1735);
DISPLAY 0.489362 (-3135 1735);
PAINT MONO (-3135 1735);
FORCEPROP 0 LASTPIN (-3125 1675) $PN BB51
J 2
(-3135 1685);
DISPLAY 0.489362 (-3135 1685);
PAINT MONO (-3135 1685);
FORCEPROP 0 LASTPIN (-3125 1625) $PN BB53
J 2
(-3135 1635);
DISPLAY 0.489362 (-3135 1635);
PAINT MONO (-3135 1635);
FORCEPROP 0 LASTPIN (-3125 1575) $PN BC52
J 2
(-3135 1585);
DISPLAY 0.489362 (-3135 1585);
PAINT MONO (-3135 1585);
FORCEPROP 0 LASTPIN (-3125 1525) $PN BC54
J 2
(-3135 1535);
DISPLAY 0.489362 (-3135 1535);
PAINT MONO (-3135 1535);
FORCEPROP 0 LASTPIN (-3125 925) $PN BN52
J 2
(-3135 935);
DISPLAY 0.489362 (-3135 935);
PAINT MONO (-3135 935);
FORCEPROP 0 LASTPIN (-3125 875) $PN BP51
J 2
(-3135 885);
DISPLAY 0.489362 (-3135 885);
PAINT MONO (-3135 885);
FORCEPROP 0 LASTPIN (-1825 625) $PN BN23
J 0
(-1815 635);
DISPLAY 0.489362 (-1815 635);
PAINT MONO (-1815 635);
FORCEPROP 0 LASTPIN (-1825 5625) $PN AA54
J 0
(-1815 5635);
DISPLAY 0.489362 (-1815 5635);
PAINT MONO (-1815 5635);
FORCEPROP 0 LASTPIN (-1825 5575) $PN AC58
J 0
(-1815 5585);
DISPLAY 0.489362 (-1815 5585);
PAINT MONO (-1815 5585);
FORCEPROP 0 LASTPIN (-1825 5525) $PN AC65
J 0
(-1815 5535);
DISPLAY 0.489362 (-1815 5535);
PAINT MONO (-1815 5535);
FORCEPROP 0 LASTPIN (-1825 5475) $PN AC72
J 0
(-1815 5485);
DISPLAY 0.489362 (-1815 5485);
PAINT MONO (-1815 5485);
FORCEPROP 0 LASTPIN (-1825 5425) $PN AD54
J 0
(-1815 5435);
DISPLAY 0.489362 (-1815 5435);
PAINT MONO (-1815 5435);
FORCEPROP 0 LASTPIN (-1825 5375) $PN AF57
J 0
(-1815 5385);
DISPLAY 0.489362 (-1815 5385);
PAINT MONO (-1815 5385);
FORCEPROP 0 LASTPIN (-1825 5325) $PN AF64
J 0
(-1815 5335);
DISPLAY 0.489362 (-1815 5335);
PAINT MONO (-1815 5335);
FORCEPROP 0 LASTPIN (-1825 5275) $PN AF71
J 0
(-1815 5285);
DISPLAY 0.489362 (-1815 5285);
PAINT MONO (-1815 5285);
FORCEPROP 0 LASTPIN (-1825 5225) $PN AH54
J 0
(-1815 5235);
DISPLAY 0.489362 (-1815 5235);
PAINT MONO (-1815 5235);
FORCEPROP 0 LASTPIN (-1825 5175) $PN AJ58
J 0
(-1815 5185);
DISPLAY 0.489362 (-1815 5185);
PAINT MONO (-1815 5185);
FORCEPROP 0 LASTPIN (-1825 5125) $PN AJ65
J 0
(-1815 5135);
DISPLAY 0.489362 (-1815 5135);
PAINT MONO (-1815 5135);
FORCEPROP 0 LASTPIN (-1825 5075) $PN AJ72
J 0
(-1815 5085);
DISPLAY 0.489362 (-1815 5085);
PAINT MONO (-1815 5085);
FORCEPROP 0 LASTPIN (-1825 5025) $PN AM54
J 0
(-1815 5035);
DISPLAY 0.489362 (-1815 5035);
PAINT MONO (-1815 5035);
FORCEPROP 0 LASTPIN (-1825 4975) $PN AM57
J 0
(-1815 4985);
DISPLAY 0.489362 (-1815 4985);
PAINT MONO (-1815 4985);
FORCEPROP 0 LASTPIN (-1825 4925) $PN AM64
J 0
(-1815 4935);
DISPLAY 0.489362 (-1815 4935);
PAINT MONO (-1815 4935);
FORCEPROP 0 LASTPIN (-1825 4875) $PN AM71
J 0
(-1815 4885);
DISPLAY 0.489362 (-1815 4885);
PAINT MONO (-1815 4885);
FORCEPROP 0 LASTPIN (-1825 4825) $PN AR58
J 0
(-1815 4835);
DISPLAY 0.489362 (-1815 4835);
PAINT MONO (-1815 4835);
FORCEPROP 0 LASTPIN (-1825 4775) $PN AR65
J 0
(-1815 4785);
DISPLAY 0.489362 (-1815 4785);
PAINT MONO (-1815 4785);
FORCEPROP 0 LASTPIN (-1825 4725) $PN AR72
J 0
(-1815 4735);
DISPLAY 0.489362 (-1815 4735);
PAINT MONO (-1815 4735);
FORCEPROP 0 LASTPIN (-3125 2625) $PN BH27
J 2
(-3135 2635);
DISPLAY 0.489362 (-3135 2635);
PAINT MONO (-3135 2635);
FORCEPROP 0 LASTPIN (-1825 4675) $PN AV57
J 0
(-1815 4685);
DISPLAY 0.489362 (-1815 4685);
PAINT MONO (-1815 4685);
FORCEPROP 0 LASTPIN (-1825 4625) $PN AV64
J 0
(-1815 4635);
DISPLAY 0.489362 (-1815 4635);
PAINT MONO (-1815 4635);
FORCEPROP 0 LASTPIN (-1825 4575) $PN AV71
J 0
(-1815 4585);
DISPLAY 0.489362 (-1815 4585);
PAINT MONO (-1815 4585);
FORCEPROP 0 LASTPIN (-1825 4525) $PN BA58
J 0
(-1815 4535);
DISPLAY 0.489362 (-1815 4535);
PAINT MONO (-1815 4535);
FORCEPROP 0 LASTPIN (-1825 4475) $PN BA65
J 0
(-1815 4485);
DISPLAY 0.489362 (-1815 4485);
PAINT MONO (-1815 4485);
FORCEPROP 0 LASTPIN (-1825 4425) $PN BA72
J 0
(-1815 4435);
DISPLAY 0.489362 (-1815 4435);
PAINT MONO (-1815 4435);
FORCEPROP 0 LASTPIN (-1825 4375) $PN BD50
J 0
(-1815 4385);
DISPLAY 0.489362 (-1815 4385);
PAINT MONO (-1815 4385);
FORCEPROP 0 LASTPIN (-1825 4325) $PN BD52
J 0
(-1815 4335);
DISPLAY 0.489362 (-1815 4335);
PAINT MONO (-1815 4335);
FORCEPROP 0 LASTPIN (-1825 4275) $PN BD54
J 0
(-1815 4285);
DISPLAY 0.489362 (-1815 4285);
PAINT MONO (-1815 4285);
FORCEPROP 0 LASTPIN (-1825 4225) $PN BF51
J 0
(-1815 4235);
DISPLAY 0.489362 (-1815 4235);
PAINT MONO (-1815 4235);
FORCEPROP 0 LASTPIN (-1825 4175) $PN BF53
J 0
(-1815 4185);
DISPLAY 0.489362 (-1815 4185);
PAINT MONO (-1815 4185);
FORCEPROP 0 LASTPIN (-1825 4125) $PN BF57
J 0
(-1815 4135);
DISPLAY 0.489362 (-1815 4135);
PAINT MONO (-1815 4135);
FORCEPROP 0 LASTPIN (-1825 4075) $PN BF64
J 0
(-1815 4085);
DISPLAY 0.489362 (-1815 4085);
PAINT MONO (-1815 4085);
FORCEPROP 0 LASTPIN (-1825 4025) $PN BF71
J 0
(-1815 4035);
DISPLAY 0.489362 (-1815 4035);
PAINT MONO (-1815 4035);
FORCEPROP 0 LASTPIN (-1825 3975) $PN BG50
J 0
(-1815 3985);
DISPLAY 0.489362 (-1815 3985);
PAINT MONO (-1815 3985);
FORCEPROP 0 LASTPIN (-1825 3925) $PN BG52
J 0
(-1815 3935);
DISPLAY 0.489362 (-1815 3935);
PAINT MONO (-1815 3935);
FORCEPROP 0 LASTPIN (-1825 3875) $PN BG54
J 0
(-1815 3885);
DISPLAY 0.489362 (-1815 3885);
PAINT MONO (-1815 3885);
FORCEPROP 0 LASTPIN (-1825 3825) $PN BH51
J 0
(-1815 3835);
DISPLAY 0.489362 (-1815 3835);
PAINT MONO (-1815 3835);
FORCEPROP 0 LASTPIN (-1825 3775) $PN BH53
J 0
(-1815 3785);
DISPLAY 0.489362 (-1815 3785);
PAINT MONO (-1815 3785);
FORCEPROP 0 LASTPIN (-1825 3725) $PN BJ50
J 0
(-1815 3735);
DISPLAY 0.489362 (-1815 3735);
PAINT MONO (-1815 3735);
FORCEPROP 0 LASTPIN (-1825 3675) $PN BJ52
J 0
(-1815 3685);
DISPLAY 0.489362 (-1815 3685);
PAINT MONO (-1815 3685);
FORCEPROP 0 LASTPIN (-1825 3625) $PN BJ54
J 0
(-1815 3635);
DISPLAY 0.489362 (-1815 3635);
PAINT MONO (-1815 3635);
FORCEPROP 0 LASTPIN (-1825 3575) $PN BJ58
J 0
(-1815 3585);
DISPLAY 0.489362 (-1815 3585);
PAINT MONO (-1815 3585);
FORCEPROP 0 LASTPIN (-1825 3525) $PN BJ65
J 0
(-1815 3535);
DISPLAY 0.489362 (-1815 3535);
PAINT MONO (-1815 3535);
FORCEPROP 0 LASTPIN (-1825 3475) $PN BJ72
J 0
(-1815 3485);
DISPLAY 0.489362 (-1815 3485);
PAINT MONO (-1815 3485);
FORCEPROP 0 LASTPIN (-1825 3425) $PN BK51
J 0
(-1815 3435);
DISPLAY 0.489362 (-1815 3435);
PAINT MONO (-1815 3435);
FORCEPROP 0 LASTPIN (-1825 3375) $PN BK53
J 0
(-1815 3385);
DISPLAY 0.489362 (-1815 3385);
PAINT MONO (-1815 3385);
FORCEPROP 0 LASTPIN (-1825 3325) $PN BL50
J 0
(-1815 3335);
DISPLAY 0.489362 (-1815 3335);
PAINT MONO (-1815 3335);
FORCEPROP 0 LASTPIN (-1825 3275) $PN BL52
J 0
(-1815 3285);
DISPLAY 0.489362 (-1815 3285);
PAINT MONO (-1815 3285);
FORCEPROP 0 LASTPIN (-1825 3225) $PN BL54
J 0
(-1815 3235);
DISPLAY 0.489362 (-1815 3235);
PAINT MONO (-1815 3235);
FORCEPROP 0 LASTPIN (-1825 3175) $PN BM51
J 0
(-1815 3185);
DISPLAY 0.489362 (-1815 3185);
PAINT MONO (-1815 3185);
FORCEPROP 0 LASTPIN (-1825 3125) $PN BM53
J 0
(-1815 3135);
DISPLAY 0.489362 (-1815 3135);
PAINT MONO (-1815 3135);
FORCEPROP 0 LASTPIN (-1825 3075) $PN BM57
J 0
(-1815 3085);
DISPLAY 0.489362 (-1815 3085);
PAINT MONO (-1815 3085);
FORCEPROP 0 LASTPIN (-1825 3025) $PN BM64
J 0
(-1815 3035);
DISPLAY 0.489362 (-1815 3035);
PAINT MONO (-1815 3035);
FORCEPROP 0 LASTPIN (-1825 2975) $PN BM71
J 0
(-1815 2985);
DISPLAY 0.489362 (-1815 2985);
PAINT MONO (-1815 2985);
FORCEPROP 0 LASTPIN (-1825 2925) $PN BN54
J 0
(-1815 2935);
DISPLAY 0.489362 (-1815 2935);
PAINT MONO (-1815 2935);
FORCEPROP 0 LASTPIN (-1825 2875) $PN BR58
J 0
(-1815 2885);
DISPLAY 0.489362 (-1815 2885);
PAINT MONO (-1815 2885);
FORCEPROP 0 LASTPIN (-1825 2825) $PN BR65
J 0
(-1815 2835);
DISPLAY 0.489362 (-1815 2835);
PAINT MONO (-1815 2835);
FORCEPROP 0 LASTPIN (-1825 2775) $PN BR72
J 0
(-1815 2785);
DISPLAY 0.489362 (-1815 2785);
PAINT MONO (-1815 2785);
FORCEPROP 0 LASTPIN (-1825 2725) $PN BV54
J 0
(-1815 2735);
DISPLAY 0.489362 (-1815 2735);
PAINT MONO (-1815 2735);
FORCEPROP 0 LASTPIN (-1825 2675) $PN BV57
J 0
(-1815 2685);
DISPLAY 0.489362 (-1815 2685);
PAINT MONO (-1815 2685);
FORCEPROP 0 LASTPIN (-1825 2625) $PN BV64
J 0
(-1815 2635);
DISPLAY 0.489362 (-1815 2635);
PAINT MONO (-1815 2635);
FORCEPROP 0 LASTPIN (-1825 2575) $PN BV71
J 0
(-1815 2585);
DISPLAY 0.489362 (-1815 2585);
PAINT MONO (-1815 2585);
FORCEPROP 0 LASTPIN (-1825 2525) $PN CA58
J 0
(-1815 2535);
DISPLAY 0.489362 (-1815 2535);
PAINT MONO (-1815 2535);
FORCEPROP 0 LASTPIN (-1825 2475) $PN CA65
J 0
(-1815 2485);
DISPLAY 0.489362 (-1815 2485);
PAINT MONO (-1815 2485);
FORCEPROP 0 LASTPIN (-1825 2425) $PN CA72
J 0
(-1815 2435);
DISPLAY 0.489362 (-1815 2435);
PAINT MONO (-1815 2435);
FORCEPROP 0 LASTPIN (-1825 2375) $PN CB54
J 0
(-1815 2385);
DISPLAY 0.489362 (-1815 2385);
PAINT MONO (-1815 2385);
FORCEPROP 0 LASTPIN (-1825 2325) $PN CD57
J 0
(-1815 2335);
DISPLAY 0.489362 (-1815 2335);
PAINT MONO (-1815 2335);
FORCEPROP 0 LASTPIN (-1825 2275) $PN CD64
J 0
(-1815 2285);
DISPLAY 0.489362 (-1815 2285);
PAINT MONO (-1815 2285);
FORCEPROP 0 LASTPIN (-1825 2225) $PN CD71
J 0
(-1815 2235);
DISPLAY 0.489362 (-1815 2235);
PAINT MONO (-1815 2235);
FORCEPROP 0 LASTPIN (-1825 2175) $PN CF54
J 0
(-1815 2185);
DISPLAY 0.489362 (-1815 2185);
PAINT MONO (-1815 2185);
FORCEPROP 0 LASTPIN (-1825 2125) $PN CG58
J 0
(-1815 2135);
DISPLAY 0.489362 (-1815 2135);
PAINT MONO (-1815 2135);
FORCEPROP 0 LASTPIN (-1825 2075) $PN CG65
J 0
(-1815 2085);
DISPLAY 0.489362 (-1815 2085);
PAINT MONO (-1815 2085);
FORCEPROP 0 LASTPIN (-1825 2025) $PN CG72
J 0
(-1815 2035);
DISPLAY 0.489362 (-1815 2035);
PAINT MONO (-1815 2035);
FORCEPROP 0 LASTPIN (-1825 1975) $PN CJ54
J 0
(-1815 1985);
DISPLAY 0.489362 (-1815 1985);
PAINT MONO (-1815 1985);
FORCEPROP 0 LASTPIN (-1825 1925) $PN CK57
J 0
(-1815 1935);
DISPLAY 0.489362 (-1815 1935);
PAINT MONO (-1815 1935);
FORCEPROP 0 LASTPIN (-1825 1875) $PN CK64
J 0
(-1815 1885);
DISPLAY 0.489362 (-1815 1885);
PAINT MONO (-1815 1885);
FORCEPROP 0 LASTPIN (-1825 1825) $PN CK71
J 0
(-1815 1835);
DISPLAY 0.489362 (-1815 1835);
PAINT MONO (-1815 1835);
FORCEPROP 0 LASTPIN (-1825 1775) $PN CM54
J 0
(-1815 1785);
DISPLAY 0.489362 (-1815 1785);
PAINT MONO (-1815 1785);
FORCEPROP 0 LASTPIN (-1825 1725) $PN CN58
J 0
(-1815 1735);
DISPLAY 0.489362 (-1815 1735);
PAINT MONO (-1815 1735);
FORCEPROP 0 LASTPIN (-1825 1675) $PN CN65
J 0
(-1815 1685);
DISPLAY 0.489362 (-1815 1685);
PAINT MONO (-1815 1685);
FORCEPROP 0 LASTPIN (-1825 1625) $PN CN72
J 0
(-1815 1635);
DISPLAY 0.489362 (-1815 1635);
PAINT MONO (-1815 1635);
FORCEPROP 0 LASTPIN (-1825 1575) $PN CT54
J 0
(-1815 1585);
DISPLAY 0.489362 (-1815 1585);
PAINT MONO (-1815 1585);
FORCEPROP 0 LASTPIN (-1825 1525) $PN CT57
J 0
(-1815 1535);
DISPLAY 0.489362 (-1815 1535);
PAINT MONO (-1815 1535);
FORCEPROP 0 LASTPIN (-1825 1475) $PN CT64
J 0
(-1815 1485);
DISPLAY 0.489362 (-1815 1485);
PAINT MONO (-1815 1485);
FORCEPROP 0 LASTPIN (-1825 1425) $PN CT71
J 0
(-1815 1435);
DISPLAY 0.489362 (-1815 1435);
PAINT MONO (-1815 1435);
FORCEPROP 0 LASTPIN (-1825 1375) $PN CW58
J 0
(-1815 1385);
DISPLAY 0.489362 (-1815 1385);
PAINT MONO (-1815 1385);
FORCEPROP 0 LASTPIN (-1825 1325) $PN CW65
J 0
(-1815 1335);
DISPLAY 0.489362 (-1815 1335);
PAINT MONO (-1815 1335);
FORCEPROP 0 LASTPIN (-1825 1275) $PN CW72
J 0
(-1815 1285);
DISPLAY 0.489362 (-1815 1285);
PAINT MONO (-1815 1285);
FORCEPROP 0 LASTPIN (-1825 1225) $PN CY54
J 0
(-1815 1235);
DISPLAY 0.489362 (-1815 1235);
PAINT MONO (-1815 1235);
FORCEPROP 0 LASTPIN (-1825 1175) $PN DB57
J 0
(-1815 1185);
DISPLAY 0.489362 (-1815 1185);
PAINT MONO (-1815 1185);
FORCEPROP 0 LASTPIN (-1825 1125) $PN DB64
J 0
(-1815 1135);
DISPLAY 0.489362 (-1815 1135);
PAINT MONO (-1815 1135);
FORCEPROP 0 LASTPIN (-1825 1075) $PN DB71
J 0
(-1815 1085);
DISPLAY 0.489362 (-1815 1085);
PAINT MONO (-1815 1085);
FORCEPROP 0 LASTPIN (-1825 1025) $PN DE58
J 0
(-1815 1035);
DISPLAY 0.489362 (-1815 1035);
PAINT MONO (-1815 1035);
FORCEPROP 0 LASTPIN (-1825 975) $PN DE65
J 0
(-1815 985);
DISPLAY 0.489362 (-1815 985);
PAINT MONO (-1815 985);
FORCEPROP 0 LASTPIN (-1825 925) $PN DE72
J 0
(-1815 935);
DISPLAY 0.489362 (-1815 935);
PAINT MONO (-1815 935);
FORCEPROP 0 LASTPIN (-1825 875) $PN DG64
J 0
(-1815 885);
DISPLAY 0.489362 (-1815 885);
PAINT MONO (-1815 885);
FORCEPROP 0 LASTPIN (-1825 825) $PN DG71
J 0
(-1815 835);
DISPLAY 0.489362 (-1815 835);
PAINT MONO (-1815 835);
FORCEPROP 0 LASTPIN (-1825 6525) $PN H57
J 0
(-1815 6535);
DISPLAY 0.489362 (-1815 6535);
PAINT MONO (-1815 6535);
FORCEPROP 0 LASTPIN (-1825 6475) $PN H64
J 0
(-1815 6485);
DISPLAY 0.489362 (-1815 6485);
PAINT MONO (-1815 6485);
FORCEPROP 0 LASTPIN (-1825 6425) $PN H71
J 0
(-1815 6435);
DISPLAY 0.489362 (-1815 6435);
PAINT MONO (-1815 6435);
FORCEPROP 0 LASTPIN (-1825 6375) $PN K54
J 0
(-1815 6385);
DISPLAY 0.489362 (-1815 6385);
PAINT MONO (-1815 6385);
FORCEPROP 0 LASTPIN (-1825 6325) $PN L58
J 0
(-1815 6335);
DISPLAY 0.489362 (-1815 6335);
PAINT MONO (-1815 6335);
FORCEPROP 0 LASTPIN (-1825 6275) $PN L65
J 0
(-1815 6285);
DISPLAY 0.489362 (-1815 6285);
PAINT MONO (-1815 6285);
FORCEPROP 0 LASTPIN (-1825 6225) $PN L72
J 0
(-1815 6235);
DISPLAY 0.489362 (-1815 6235);
PAINT MONO (-1815 6235);
FORCEPROP 0 LASTPIN (-1825 6175) $PN P54
J 0
(-1815 6185);
DISPLAY 0.489362 (-1815 6185);
PAINT MONO (-1815 6185);
FORCEPROP 0 LASTPIN (-1825 6125) $PN P57
J 0
(-1815 6135);
DISPLAY 0.489362 (-1815 6135);
PAINT MONO (-1815 6135);
FORCEPROP 0 LASTPIN (-1825 6075) $PN P64
J 0
(-1815 6085);
DISPLAY 0.489362 (-1815 6085);
PAINT MONO (-1815 6085);
FORCEPROP 0 LASTPIN (-1825 6025) $PN P71
J 0
(-1815 6035);
DISPLAY 0.489362 (-1815 6035);
PAINT MONO (-1815 6035);
FORCEPROP 0 LASTPIN (-1825 5975) $PN U58
J 0
(-1815 5985);
DISPLAY 0.489362 (-1815 5985);
PAINT MONO (-1815 5985);
FORCEPROP 0 LASTPIN (-1825 5925) $PN U65
J 0
(-1815 5935);
DISPLAY 0.489362 (-1815 5935);
PAINT MONO (-1815 5935);
FORCEPROP 0 LASTPIN (-1825 5875) $PN U72
J 0
(-1815 5885);
DISPLAY 0.489362 (-1815 5885);
PAINT MONO (-1815 5885);
FORCEPROP 0 LASTPIN (-1825 5825) $PN V54
J 0
(-1815 5835);
DISPLAY 0.489362 (-1815 5835);
PAINT MONO (-1815 5835);
FORCEPROP 0 LASTPIN (-1825 5775) $PN Y57
J 0
(-1815 5785);
DISPLAY 0.489362 (-1815 5785);
PAINT MONO (-1815 5785);
FORCEPROP 0 LASTPIN (-1825 5725) $PN Y64
J 0
(-1815 5735);
DISPLAY 0.489362 (-1815 5735);
PAINT MONO (-1815 5735);
FORCEPROP 0 LASTPIN (-1825 5675) $PN Y71
J 0
(-1815 5685);
DISPLAY 0.489362 (-1815 5685);
PAINT MONO (-1815 5685);
FORCEPROP 2 LAST PART_TYPE SMLF
J 0
(-2825 6650);
DISPLAY 1.021277 (-2825 6650);
FORCEPROP 1 LAST MATERIAL IO
J 0
(-2970 6657);
DISPLAY 0.489362 (-2970 6657);
PAINT SKYBLUE (-2970 6657);
FORCEPROP 2 LAST VALUE SOCKET6096_13568-001
J 0
(-2600 6650);
DISPLAY 0.489362 (-2600 6650);
PAINT SKYBLUE (-2600 6650);
FORCEPROP 1 LAST PART_NUMBER DGA^6000030
J 0
(-2825 6700);
DISPLAY 0.489362 (-2825 6700);
PAINT SKYBLUE (-2825 6700);
FORCEPROP 2 LAST CDS_LIB pure_quanta
J 0
(-2475 3550);
DISPLAY INVISIBLE (-2475 3550);
FORCEPROP 1 LAST CDS_LMAN_SYM_OUTLINE -500,3075,500,-3075
J 0
(-2475 3550);
DISPLAY 0.468085 (-2475 3550);
PAINT GREEN (-2475 3550);
DISPLAY INVISIBLE (-2475 3550);
FORCEPROP 1 LAST NEEDS_NO_SIZE TRUE
J 0
(-2475 3550);
DISPLAY 0.723404 (-2475 3550);
PAINT GREEN (-2475 3550);
DISPLAY INVISIBLE (-2475 3550);
FORCEPROP 1 LAST PATH I28
J 0
(-2475 3550);
DISPLAY 0.723404 (-2475 3550);
PAINT GREEN (-2475 3550);
DISPLAY INVISIBLE (-2475 3550);
FORCEADD GENOA_SP5..23
(-725 4350);
FORCEPROP 1 LAST LOCATION U25
J 0
(-1275 6500);
DISPLAY 0.489362 (-1275 6500);
PAINT SKYBLUE (-1275 6500);
FORCEPROP 0 LAST $SEC 23
J 0
(-1250 6700);
DISPLAY 0.680851 (-1250 6700);
PAINT MONO (-1250 6700);
DISPLAY INVISIBLE (-1250 6700);
FORCEPROP 0 LAST CDS_SEC 23
J 0
(-750 6625);
DISPLAY 1.021277 (-750 6625);
DISPLAY INVISIBLE (-750 6625);
FORCEPROP 0 LASTPIN (-1425 5700) $PN A31
J 2
(-1435 5710);
DISPLAY 0.489362 (-1435 5710);
PAINT MONO (-1435 5710);
FORCEPROP 0 LASTPIN (-1425 5650) $PN A35
J 2
(-1435 5660);
DISPLAY 0.489362 (-1435 5660);
PAINT MONO (-1435 5660);
FORCEPROP 0 LASTPIN (-1425 5600) $PN A41
J 2
(-1435 5610);
DISPLAY 0.489362 (-1435 5610);
PAINT MONO (-1435 5610);
FORCEPROP 0 LASTPIN (-1425 5550) $PN A42
J 2
(-1435 5560);
DISPLAY 0.489362 (-1435 5560);
PAINT MONO (-1435 5560);
FORCEPROP 0 LASTPIN (-1425 5500) $PN A45
J 2
(-1435 5510);
DISPLAY 0.489362 (-1435 5510);
PAINT MONO (-1435 5510);
FORCEPROP 0 LASTPIN (-1425 5450) $PN A48
J 2
(-1435 5460);
DISPLAY 0.489362 (-1435 5460);
PAINT MONO (-1435 5460);
FORCEPROP 0 LASTPIN (-1425 5400) $PN A50
J 2
(-1435 5410);
DISPLAY 0.489362 (-1435 5410);
PAINT MONO (-1435 5410);
FORCEPROP 0 LASTPIN (-1425 5350) $PN A51
J 2
(-1435 5360);
DISPLAY 0.489362 (-1435 5360);
PAINT MONO (-1435 5360);
FORCEPROP 0 LASTPIN (-1425 5300) $PN A54
J 2
(-1435 5310);
DISPLAY 0.489362 (-1435 5310);
PAINT MONO (-1435 5310);
FORCEPROP 0 LASTPIN (-1425 5250) $PN A55
J 2
(-1435 5260);
DISPLAY 0.489362 (-1435 5260);
PAINT MONO (-1435 5260);
FORCEPROP 0 LASTPIN (-1425 5200) $PN A56
J 2
(-1435 5210);
DISPLAY 0.489362 (-1435 5210);
PAINT MONO (-1435 5210);
FORCEPROP 0 LASTPIN (-1425 5150) $PN A57
J 2
(-1435 5160);
DISPLAY 0.489362 (-1435 5160);
PAINT MONO (-1435 5160);
FORCEPROP 0 LASTPIN (-1425 5100) $PN A59
J 2
(-1435 5110);
DISPLAY 0.489362 (-1435 5110);
PAINT MONO (-1435 5110);
FORCEPROP 0 LASTPIN (-1425 5050) $PN A60
J 2
(-1435 5060);
DISPLAY 0.489362 (-1435 5060);
PAINT MONO (-1435 5060);
FORCEPROP 0 LASTPIN (-1425 5000) $PN B40
J 2
(-1435 5010);
DISPLAY 0.489362 (-1435 5010);
PAINT MONO (-1435 5010);
FORCEPROP 0 LASTPIN (-1425 4100) $PN BD4
J 2
(-1435 4110);
DISPLAY 0.489362 (-1435 4110);
PAINT MONO (-1435 4110);
FORCEPROP 0 LASTPIN (-1425 4050) $PN BD7
J 2
(-1435 4060);
DISPLAY 0.489362 (-1435 4060);
PAINT MONO (-1435 4060);
FORCEPROP 0 LASTPIN (-1425 4000) $PN BD11
J 2
(-1435 4010);
DISPLAY 0.489362 (-1435 4010);
PAINT MONO (-1435 4010);
FORCEPROP 0 LASTPIN (-1425 3950) $PN BD14
J 2
(-1435 3960);
DISPLAY 0.489362 (-1435 3960);
PAINT MONO (-1435 3960);
FORCEPROP 0 LASTPIN (-1425 3900) $PN BD18
J 2
(-1435 3910);
DISPLAY 0.489362 (-1435 3910);
PAINT MONO (-1435 3910);
FORCEPROP 0 LASTPIN (-1425 3850) $PN BD21
J 2
(-1435 3860);
DISPLAY 0.489362 (-1435 3860);
PAINT MONO (-1435 3860);
FORCEPROP 0 LASTPIN (-1425 3800) $PN BD55
J 2
(-1435 3810);
DISPLAY 0.489362 (-1435 3810);
PAINT MONO (-1435 3810);
FORCEPROP 0 LASTPIN (-1425 3750) $PN BD58
J 2
(-1435 3760);
DISPLAY 0.489362 (-1435 3760);
PAINT MONO (-1435 3760);
FORCEPROP 0 LASTPIN (-1425 3700) $PN BD62
J 2
(-1435 3710);
DISPLAY 0.489362 (-1435 3710);
PAINT MONO (-1435 3710);
FORCEPROP 0 LASTPIN (-1425 3650) $PN BD65
J 2
(-1435 3660);
DISPLAY 0.489362 (-1435 3660);
PAINT MONO (-1435 3660);
FORCEPROP 0 LASTPIN (-1425 3600) $PN BD69
J 2
(-1435 3610);
DISPLAY 0.489362 (-1435 3610);
PAINT MONO (-1435 3610);
FORCEPROP 0 LASTPIN (-1425 3550) $PN BD72
J 2
(-1435 3560);
DISPLAY 0.489362 (-1435 3560);
PAINT MONO (-1435 3560);
FORCEPROP 0 LASTPIN (-1425 4950) $PN C31
J 2
(-1435 4960);
DISPLAY 0.489362 (-1435 4960);
PAINT MONO (-1435 4960);
FORCEPROP 0 LASTPIN (-1425 4900) $PN C34
J 2
(-1435 4910);
DISPLAY 0.489362 (-1435 4910);
PAINT MONO (-1435 4910);
FORCEPROP 0 LASTPIN (-1425 4850) $PN C35
J 2
(-1435 4860);
DISPLAY 0.489362 (-1435 4860);
PAINT MONO (-1435 4860);
FORCEPROP 0 LASTPIN (-1425 4800) $PN C53
J 2
(-1435 4810);
DISPLAY 0.489362 (-1435 4810);
PAINT MONO (-1435 4810);
FORCEPROP 0 LASTPIN (-1425 4750) $PN C54
J 2
(-1435 4760);
DISPLAY 0.489362 (-1435 4760);
PAINT MONO (-1435 4760);
FORCEPROP 0 LASTPIN (-1425 4700) $PN D4
J 2
(-1435 4710);
DISPLAY 0.489362 (-1435 4710);
PAINT MONO (-1435 4710);
FORCEPROP 0 LASTPIN (-1425 4650) $PN D8
J 2
(-1435 4660);
DISPLAY 0.489362 (-1435 4660);
PAINT MONO (-1435 4660);
FORCEPROP 0 LASTPIN (-1425 4600) $PN D11
J 2
(-1435 4610);
DISPLAY 0.489362 (-1435 4610);
PAINT MONO (-1435 4610);
FORCEPROP 0 LASTPIN (-1425 4550) $PN D22
J 2
(-1435 4560);
DISPLAY 0.489362 (-1435 4560);
PAINT MONO (-1435 4560);
FORCEPROP 0 LASTPIN (-1425 4500) $PN D34
J 2
(-1435 4510);
DISPLAY 0.489362 (-1435 4510);
PAINT MONO (-1435 4510);
FORCEPROP 0 LASTPIN (-1425 4450) $PN D36
J 2
(-1435 4460);
DISPLAY 0.489362 (-1435 4460);
PAINT MONO (-1435 4460);
FORCEPROP 0 LASTPIN (-1425 4400) $PN D58
J 2
(-1435 4410);
DISPLAY 0.489362 (-1435 4410);
PAINT MONO (-1435 4410);
FORCEPROP 0 LASTPIN (-1425 4350) $PN D62
J 2
(-1435 4360);
DISPLAY 0.489362 (-1435 4360);
PAINT MONO (-1435 4360);
FORCEPROP 0 LASTPIN (-1425 4300) $PN D65
J 2
(-1435 4310);
DISPLAY 0.489362 (-1435 4310);
PAINT MONO (-1435 4310);
FORCEPROP 0 LASTPIN (-1425 4250) $PN D72
J 2
(-1435 4260);
DISPLAY 0.489362 (-1435 4260);
PAINT MONO (-1435 4260);
FORCEPROP 0 LASTPIN (-1425 3500) $PN DG17
J 2
(-1435 3510);
DISPLAY 0.489362 (-1435 3510);
PAINT MONO (-1435 3510);
FORCEPROP 0 LASTPIN (-1425 3450) $PN DH17
J 2
(-1435 3460);
DISPLAY 0.489362 (-1435 3460);
PAINT MONO (-1435 3460);
FORCEPROP 0 LASTPIN (-1425 3400) $PN DH21
J 2
(-1435 3410);
DISPLAY 0.489362 (-1435 3410);
PAINT MONO (-1435 3410);
FORCEPROP 0 LASTPIN (-1425 3350) $PN DJ4
J 2
(-1435 3360);
DISPLAY 0.489362 (-1435 3360);
PAINT MONO (-1435 3360);
FORCEPROP 0 LASTPIN (-1425 4200) $PN E33
J 2
(-1435 4210);
DISPLAY 0.489362 (-1435 4210);
PAINT MONO (-1435 4210);
FORCEPROP 0 LASTPIN (-1425 4150) $PN E36
J 2
(-1435 4160);
DISPLAY 0.489362 (-1435 4160);
PAINT MONO (-1435 4160);
FORCEPROP 0 LASTPIN (-1425 3150) $PN C58
J 2
(-1435 3160);
DISPLAY 0.489362 (-1435 3160);
PAINT MONO (-1435 3160);
FORCEPROP 0 LASTPIN (-1425 2900) $PN DH13
J 2
(-1435 2910);
DISPLAY 0.489362 (-1435 2910);
PAINT MONO (-1435 2910);
FORCEPROP 0 LASTPIN (-1425 3000) $PN DF41
J 2
(-1435 3010);
DISPLAY 0.489362 (-1435 3010);
PAINT MONO (-1435 3010);
FORCEPROP 0 LASTPIN (-1425 3200) $PN C23
J 2
(-1435 3210);
DISPLAY 0.489362 (-1435 3210);
PAINT MONO (-1435 3210);
FORCEPROP 0 LASTPIN (-1425 3100) $PN C59
J 2
(-1435 3110);
DISPLAY 0.489362 (-1435 3110);
PAINT MONO (-1435 3110);
FORCEPROP 0 LASTPIN (-1425 2850) $PN DH14
J 2
(-1435 2860);
DISPLAY 0.489362 (-1435 2860);
PAINT MONO (-1435 2860);
FORCEPROP 0 LASTPIN (-1425 2950) $PN DG42
J 2
(-1435 2960);
DISPLAY 0.489362 (-1435 2960);
PAINT MONO (-1435 2960);
FORCEPROP 0 LASTPIN (-1425 3050) $PN D23
J 2
(-1435 3060);
DISPLAY 0.489362 (-1435 3060);
PAINT MONO (-1435 3060);
FORCEPROP 0 LASTPIN (-1425 2700) $PN B36
J 2
(-1435 2710);
DISPLAY 0.489362 (-1435 2710);
PAINT MONO (-1435 2710);
FORCEPROP 0 LASTPIN (-1425 2800) $PN DJ57
J 2
(-1435 2810);
DISPLAY 0.489362 (-1435 2810);
PAINT MONO (-1435 2810);
FORCEPROP 2 LAST PART_TYPE SMLF
J 0
(-1275 6650);
DISPLAY 1.021277 (-1275 6650);
FORCEPROP 1 LAST MATERIAL IO
J 0
(-1270 6382);
DISPLAY 0.489362 (-1270 6382);
PAINT SKYBLUE (-1270 6382);
FORCEPROP 2 LAST VALUE SOCKET6096_13568-001
J 0
(-1275 6450);
DISPLAY 0.489362 (-1275 6450);
PAINT SKYBLUE (-1275 6450);
FORCEPROP 1 LAST PART_NUMBER DGA^6000030
J 0
(-1275 6575);
DISPLAY 0.489362 (-1275 6575);
PAINT SKYBLUE (-1275 6575);
FORCEPROP 1 LAST CDS_LMAN_SYM_OUTLINE -550,2000,550,-2000
J 0
(-725 4350);
DISPLAY 0.468085 (-725 4350);
PAINT GREEN (-725 4350);
DISPLAY INVISIBLE (-725 4350);
FORCEPROP 2 LAST CDS_LIB pure_quanta
J 0
(-725 4350);
DISPLAY INVISIBLE (-725 4350);
FORCEPROP 1 LAST NEEDS_NO_SIZE TRUE
J 0
(-725 4350);
DISPLAY 0.723404 (-725 4350);
PAINT GREEN (-725 4350);
DISPLAY INVISIBLE (-725 4350);
FORCEPROP 1 LAST PATH I29
J 0
(-725 4350);
DISPLAY 0.723404 (-725 4350);
PAINT GREEN (-725 4350);
DISPLAY INVISIBLE (-725 4350);
FORCEADD VCC_CORE..1
(-1675 6625);
FORCEPROP 3 LASTPIN (-1675 6575) SIG_NAME PVDDIO_P0\g
J 0
(-1665 6585);
DISPLAY 0.659574 (-1665 6585);
PAINT MONO (-1665 6585);
DISPLAY INVISIBLE (-1665 6585);
FORCEPROP 1 LAST HDL_POWER PVDDIO_P0
J 1
(-1675 6675);
DISPLAY 0.489362 (-1675 6675);
PAINT GREEN (-1675 6675);
FORCEPROP 2 LAST CDS_LIB pure_quanta_power
J 0
(-1675 6625);
DISPLAY INVISIBLE (-1675 6625);
FORCEPROP 1 LAST PATH I40
J 0
(-1625 6650);
DISPLAY 0.872340 (-1625 6650);
PAINT AQUA (-1625 6650);
DISPLAY INVISIBLE (-1625 6650);
FORCEADD UNIVERSAL_POWER..1
(-1475 825);
FORCEPROP 3 LASTPIN (-1475 775) SIG_NAME P1V5_BAT\g
J 0
(-1465 785);
DISPLAY 0.659574 (-1465 785);
PAINT MONO (-1465 785);
DISPLAY INVISIBLE (-1465 785);
FORCEPROP 1 LAST HDL_POWER P1V5_BAT
J 1
(-1475 875);
DISPLAY 0.489362 (-1475 875);
PAINT GREEN (-1475 875);
FORCEPROP 2 LAST CDS_LIB pure_quanta_power
J 0
(-1475 825);
DISPLAY INVISIBLE (-1475 825);
FORCEPROP 1 LAST PATH I41
J 0
(-1425 850);
DISPLAY 0.872340 (-1425 850);
PAINT AQUA (-1425 850);
DISPLAY INVISIBLE (-1425 850);
FORCEADD GENOA_SP5..24
(-8050 3325);
FORCEPROP 1 LAST LOCATION U25
J 0
(-8550 6600);
DISPLAY 0.489362 (-8550 6600);
PAINT SKYBLUE (-8550 6600);
FORCEPROP 0 LAST $SEC 24
J 0
(-8525 6825);
DISPLAY 0.680851 (-8525 6825);
PAINT MONO (-8525 6825);
DISPLAY INVISIBLE (-8525 6825);
FORCEPROP 0 LAST CDS_SEC 24
J 0
(-8550 6700);
DISPLAY 1.021277 (-8550 6700);
DISPLAY INVISIBLE (-8550 6700);
FORCEPROP 0 LASTPIN (-7400 5925) $PN AB23
J 0
(-7390 5935);
DISPLAY 0.489362 (-7390 5935);
PAINT MONO (-7390 5935);
FORCEPROP 0 LASTPIN (-7400 5875) $PN AB24
J 0
(-7390 5885);
DISPLAY 0.489362 (-7390 5885);
PAINT MONO (-7390 5885);
FORCEPROP 0 LASTPIN (-7400 5825) $PN AB26
J 0
(-7390 5835);
DISPLAY 0.489362 (-7390 5835);
PAINT MONO (-7390 5835);
FORCEPROP 0 LASTPIN (-7400 5775) $PN AB27
J 0
(-7390 5785);
DISPLAY 0.489362 (-7390 5785);
PAINT MONO (-7390 5785);
FORCEPROP 0 LASTPIN (-7400 5725) $PN AB29
J 0
(-7390 5735);
DISPLAY 0.489362 (-7390 5735);
PAINT MONO (-7390 5735);
FORCEPROP 0 LASTPIN (-7400 5675) $PN AB30
J 0
(-7390 5685);
DISPLAY 0.489362 (-7390 5685);
PAINT MONO (-7390 5685);
FORCEPROP 0 LASTPIN (-7400 5625) $PN AB32
J 0
(-7390 5635);
DISPLAY 0.489362 (-7390 5635);
PAINT MONO (-7390 5635);
FORCEPROP 0 LASTPIN (-7400 5575) $PN AB33
J 0
(-7390 5585);
DISPLAY 0.489362 (-7390 5585);
PAINT MONO (-7390 5585);
FORCEPROP 0 LASTPIN (-7400 5525) $PN AB43
J 0
(-7390 5535);
DISPLAY 0.489362 (-7390 5535);
PAINT MONO (-7390 5535);
FORCEPROP 0 LASTPIN (-7400 5475) $PN AB44
J 0
(-7390 5485);
DISPLAY 0.489362 (-7390 5485);
PAINT MONO (-7390 5485);
FORCEPROP 0 LASTPIN (-7400 5425) $PN AB46
J 0
(-7390 5435);
DISPLAY 0.489362 (-7390 5435);
PAINT MONO (-7390 5435);
FORCEPROP 0 LASTPIN (-7400 5375) $PN AB47
J 0
(-7390 5385);
DISPLAY 0.489362 (-7390 5385);
PAINT MONO (-7390 5385);
FORCEPROP 0 LASTPIN (-7400 5325) $PN AB49
J 0
(-7390 5335);
DISPLAY 0.489362 (-7390 5335);
PAINT MONO (-7390 5335);
FORCEPROP 0 LASTPIN (-7400 5275) $PN AB50
J 0
(-7390 5285);
DISPLAY 0.489362 (-7390 5285);
PAINT MONO (-7390 5285);
FORCEPROP 0 LASTPIN (-7400 5225) $PN AB52
J 0
(-7390 5235);
DISPLAY 0.489362 (-7390 5235);
PAINT MONO (-7390 5235);
FORCEPROP 0 LASTPIN (-7400 5175) $PN AB53
J 0
(-7390 5185);
DISPLAY 0.489362 (-7390 5185);
PAINT MONO (-7390 5185);
FORCEPROP 0 LASTPIN (-7400 5125) $PN AC35
J 0
(-7390 5135);
DISPLAY 0.489362 (-7390 5135);
PAINT MONO (-7390 5135);
FORCEPROP 0 LASTPIN (-7400 5075) $PN AC36
J 0
(-7390 5085);
DISPLAY 0.489362 (-7390 5085);
PAINT MONO (-7390 5085);
FORCEPROP 0 LASTPIN (-7400 5025) $PN AC40
J 0
(-7390 5035);
DISPLAY 0.489362 (-7390 5035);
PAINT MONO (-7390 5035);
FORCEPROP 0 LASTPIN (-7400 4975) $PN AC41
J 0
(-7390 4985);
DISPLAY 0.489362 (-7390 4985);
PAINT MONO (-7390 4985);
FORCEPROP 0 LASTPIN (-7400 4925) $PN AF23
J 0
(-7390 4935);
DISPLAY 0.489362 (-7390 4935);
PAINT MONO (-7390 4935);
FORCEPROP 0 LASTPIN (-7400 4875) $PN AF24
J 0
(-7390 4885);
DISPLAY 0.489362 (-7390 4885);
PAINT MONO (-7390 4885);
FORCEPROP 0 LASTPIN (-7400 4825) $PN AF26
J 0
(-7390 4835);
DISPLAY 0.489362 (-7390 4835);
PAINT MONO (-7390 4835);
FORCEPROP 0 LASTPIN (-7400 4775) $PN AF27
J 0
(-7390 4785);
DISPLAY 0.489362 (-7390 4785);
PAINT MONO (-7390 4785);
FORCEPROP 0 LASTPIN (-7400 4725) $PN AF29
J 0
(-7390 4735);
DISPLAY 0.489362 (-7390 4735);
PAINT MONO (-7390 4735);
FORCEPROP 0 LASTPIN (-7400 4675) $PN AF30
J 0
(-7390 4685);
DISPLAY 0.489362 (-7390 4685);
PAINT MONO (-7390 4685);
FORCEPROP 0 LASTPIN (-7400 4625) $PN AF32
J 0
(-7390 4635);
DISPLAY 0.489362 (-7390 4635);
PAINT MONO (-7390 4635);
FORCEPROP 0 LASTPIN (-7400 4575) $PN AF33
J 0
(-7390 4585);
DISPLAY 0.489362 (-7390 4585);
PAINT MONO (-7390 4585);
FORCEPROP 0 LASTPIN (-7400 4525) $PN AF43
J 0
(-7390 4535);
DISPLAY 0.489362 (-7390 4535);
PAINT MONO (-7390 4535);
FORCEPROP 0 LASTPIN (-7400 4475) $PN AF44
J 0
(-7390 4485);
DISPLAY 0.489362 (-7390 4485);
PAINT MONO (-7390 4485);
FORCEPROP 0 LASTPIN (-7400 4425) $PN AF46
J 0
(-7390 4435);
DISPLAY 0.489362 (-7390 4435);
PAINT MONO (-7390 4435);
FORCEPROP 0 LASTPIN (-7400 4375) $PN AF47
J 0
(-7390 4385);
DISPLAY 0.489362 (-7390 4385);
PAINT MONO (-7390 4385);
FORCEPROP 0 LASTPIN (-7400 4325) $PN AF49
J 0
(-7390 4335);
DISPLAY 0.489362 (-7390 4335);
PAINT MONO (-7390 4335);
FORCEPROP 0 LASTPIN (-7400 4275) $PN AF50
J 0
(-7390 4285);
DISPLAY 0.489362 (-7390 4285);
PAINT MONO (-7390 4285);
FORCEPROP 0 LASTPIN (-7400 4225) $PN AF52
J 0
(-7390 4235);
DISPLAY 0.489362 (-7390 4235);
PAINT MONO (-7390 4235);
FORCEPROP 0 LASTPIN (-7400 4175) $PN AF53
J 0
(-7390 4185);
DISPLAY 0.489362 (-7390 4185);
PAINT MONO (-7390 4185);
FORCEPROP 0 LASTPIN (-7400 4125) $PN AG35
J 0
(-7390 4135);
DISPLAY 0.489362 (-7390 4135);
PAINT MONO (-7390 4135);
FORCEPROP 0 LASTPIN (-7400 4075) $PN AG36
J 0
(-7390 4085);
DISPLAY 0.489362 (-7390 4085);
PAINT MONO (-7390 4085);
FORCEPROP 0 LASTPIN (-7400 4025) $PN AG40
J 0
(-7390 4035);
DISPLAY 0.489362 (-7390 4035);
PAINT MONO (-7390 4035);
FORCEPROP 0 LASTPIN (-7400 3975) $PN AG41
J 0
(-7390 3985);
DISPLAY 0.489362 (-7390 3985);
PAINT MONO (-7390 3985);
FORCEPROP 0 LASTPIN (-7400 3925) $PN AK23
J 0
(-7390 3935);
DISPLAY 0.489362 (-7390 3935);
PAINT MONO (-7390 3935);
FORCEPROP 0 LASTPIN (-7400 3875) $PN AK24
J 0
(-7390 3885);
DISPLAY 0.489362 (-7390 3885);
PAINT MONO (-7390 3885);
FORCEPROP 0 LASTPIN (-7400 3825) $PN AK26
J 0
(-7390 3835);
DISPLAY 0.489362 (-7390 3835);
PAINT MONO (-7390 3835);
FORCEPROP 0 LASTPIN (-7400 3775) $PN AK27
J 0
(-7390 3785);
DISPLAY 0.489362 (-7390 3785);
PAINT MONO (-7390 3785);
FORCEPROP 0 LASTPIN (-7400 3725) $PN AK29
J 0
(-7390 3735);
DISPLAY 0.489362 (-7390 3735);
PAINT MONO (-7390 3735);
FORCEPROP 0 LASTPIN (-7400 3675) $PN AK30
J 0
(-7390 3685);
DISPLAY 0.489362 (-7390 3685);
PAINT MONO (-7390 3685);
FORCEPROP 0 LASTPIN (-7400 3625) $PN AK32
J 0
(-7390 3635);
DISPLAY 0.489362 (-7390 3635);
PAINT MONO (-7390 3635);
FORCEPROP 0 LASTPIN (-7400 3575) $PN AK33
J 0
(-7390 3585);
DISPLAY 0.489362 (-7390 3585);
PAINT MONO (-7390 3585);
FORCEPROP 0 LASTPIN (-7400 3525) $PN AK43
J 0
(-7390 3535);
DISPLAY 0.489362 (-7390 3535);
PAINT MONO (-7390 3535);
FORCEPROP 0 LASTPIN (-7400 3475) $PN AK44
J 0
(-7390 3485);
DISPLAY 0.489362 (-7390 3485);
PAINT MONO (-7390 3485);
FORCEPROP 0 LASTPIN (-7400 3425) $PN AK46
J 0
(-7390 3435);
DISPLAY 0.489362 (-7390 3435);
PAINT MONO (-7390 3435);
FORCEPROP 0 LASTPIN (-7400 3375) $PN AK47
J 0
(-7390 3385);
DISPLAY 0.489362 (-7390 3385);
PAINT MONO (-7390 3385);
FORCEPROP 0 LASTPIN (-7400 3325) $PN AK49
J 0
(-7390 3335);
DISPLAY 0.489362 (-7390 3335);
PAINT MONO (-7390 3335);
FORCEPROP 0 LASTPIN (-7400 3275) $PN AK50
J 0
(-7390 3285);
DISPLAY 0.489362 (-7390 3285);
PAINT MONO (-7390 3285);
FORCEPROP 0 LASTPIN (-7400 3225) $PN AK52
J 0
(-7390 3235);
DISPLAY 0.489362 (-7390 3235);
PAINT MONO (-7390 3235);
FORCEPROP 0 LASTPIN (-7400 3175) $PN AK53
J 0
(-7390 3185);
DISPLAY 0.489362 (-7390 3185);
PAINT MONO (-7390 3185);
FORCEPROP 0 LASTPIN (-7400 3125) $PN AL35
J 0
(-7390 3135);
DISPLAY 0.489362 (-7390 3135);
PAINT MONO (-7390 3135);
FORCEPROP 0 LASTPIN (-7400 3075) $PN AL36
J 0
(-7390 3085);
DISPLAY 0.489362 (-7390 3085);
PAINT MONO (-7390 3085);
FORCEPROP 0 LASTPIN (-7400 3025) $PN AL40
J 0
(-7390 3035);
DISPLAY 0.489362 (-7390 3035);
PAINT MONO (-7390 3035);
FORCEPROP 0 LASTPIN (-7400 2975) $PN AL41
J 0
(-7390 2985);
DISPLAY 0.489362 (-7390 2985);
PAINT MONO (-7390 2985);
FORCEPROP 0 LASTPIN (-7400 2925) $PN AP23
J 0
(-7390 2935);
DISPLAY 0.489362 (-7390 2935);
PAINT MONO (-7390 2935);
FORCEPROP 0 LASTPIN (-7400 2875) $PN AP24
J 0
(-7390 2885);
DISPLAY 0.489362 (-7390 2885);
PAINT MONO (-7390 2885);
FORCEPROP 0 LASTPIN (-7400 2825) $PN AP26
J 0
(-7390 2835);
DISPLAY 0.489362 (-7390 2835);
PAINT MONO (-7390 2835);
FORCEPROP 0 LASTPIN (-7400 2775) $PN AP27
J 0
(-7390 2785);
DISPLAY 0.489362 (-7390 2785);
PAINT MONO (-7390 2785);
FORCEPROP 0 LASTPIN (-7400 2725) $PN AP29
J 0
(-7390 2735);
DISPLAY 0.489362 (-7390 2735);
PAINT MONO (-7390 2735);
FORCEPROP 0 LASTPIN (-7400 2675) $PN AP30
J 0
(-7390 2685);
DISPLAY 0.489362 (-7390 2685);
PAINT MONO (-7390 2685);
FORCEPROP 0 LASTPIN (-7400 2625) $PN AP32
J 0
(-7390 2635);
DISPLAY 0.489362 (-7390 2635);
PAINT MONO (-7390 2635);
FORCEPROP 0 LASTPIN (-7400 2575) $PN AP33
J 0
(-7390 2585);
DISPLAY 0.489362 (-7390 2585);
PAINT MONO (-7390 2585);
FORCEPROP 0 LASTPIN (-7400 2525) $PN AP43
J 0
(-7390 2535);
DISPLAY 0.489362 (-7390 2535);
PAINT MONO (-7390 2535);
FORCEPROP 0 LASTPIN (-7400 2475) $PN AP44
J 0
(-7390 2485);
DISPLAY 0.489362 (-7390 2485);
PAINT MONO (-7390 2485);
FORCEPROP 0 LASTPIN (-7400 2425) $PN AP46
J 0
(-7390 2435);
DISPLAY 0.489362 (-7390 2435);
PAINT MONO (-7390 2435);
FORCEPROP 0 LASTPIN (-7400 2375) $PN AP47
J 0
(-7390 2385);
DISPLAY 0.489362 (-7390 2385);
PAINT MONO (-7390 2385);
FORCEPROP 0 LASTPIN (-7400 2325) $PN AP49
J 0
(-7390 2335);
DISPLAY 0.489362 (-7390 2335);
PAINT MONO (-7390 2335);
FORCEPROP 0 LASTPIN (-7400 2275) $PN AP50
J 0
(-7390 2285);
DISPLAY 0.489362 (-7390 2285);
PAINT MONO (-7390 2285);
FORCEPROP 0 LASTPIN (-7400 2225) $PN AP52
J 0
(-7390 2235);
DISPLAY 0.489362 (-7390 2235);
PAINT MONO (-7390 2235);
FORCEPROP 0 LASTPIN (-7400 2175) $PN AP53
J 0
(-7390 2185);
DISPLAY 0.489362 (-7390 2185);
PAINT MONO (-7390 2185);
FORCEPROP 0 LASTPIN (-7400 2125) $PN AR23
J 0
(-7390 2135);
DISPLAY 0.489362 (-7390 2135);
PAINT MONO (-7390 2135);
FORCEPROP 0 LASTPIN (-7400 2075) $PN AR25
J 0
(-7390 2085);
DISPLAY 0.489362 (-7390 2085);
PAINT MONO (-7390 2085);
FORCEPROP 0 LASTPIN (-7400 2025) $PN AR27
J 0
(-7390 2035);
DISPLAY 0.489362 (-7390 2035);
PAINT MONO (-7390 2035);
FORCEPROP 0 LASTPIN (-7400 1975) $PN AR29
J 0
(-7390 1985);
DISPLAY 0.489362 (-7390 1985);
PAINT MONO (-7390 1985);
FORCEPROP 0 LASTPIN (-7400 1925) $PN AR31
J 0
(-7390 1935);
DISPLAY 0.489362 (-7390 1935);
PAINT MONO (-7390 1935);
FORCEPROP 0 LASTPIN (-7400 1875) $PN AR33
J 0
(-7390 1885);
DISPLAY 0.489362 (-7390 1885);
PAINT MONO (-7390 1885);
FORCEPROP 0 LASTPIN (-7400 1825) $PN AR35
J 0
(-7390 1835);
DISPLAY 0.489362 (-7390 1835);
PAINT MONO (-7390 1835);
FORCEPROP 0 LASTPIN (-7400 1775) $PN AR40
J 0
(-7390 1785);
DISPLAY 0.489362 (-7390 1785);
PAINT MONO (-7390 1785);
FORCEPROP 0 LASTPIN (-7400 1725) $PN AR42
J 0
(-7390 1735);
DISPLAY 0.489362 (-7390 1735);
PAINT MONO (-7390 1735);
FORCEPROP 0 LASTPIN (-7400 1675) $PN AR44
J 0
(-7390 1685);
DISPLAY 0.489362 (-7390 1685);
PAINT MONO (-7390 1685);
FORCEPROP 0 LASTPIN (-7400 1625) $PN AR46
J 0
(-7390 1635);
DISPLAY 0.489362 (-7390 1635);
PAINT MONO (-7390 1635);
FORCEPROP 0 LASTPIN (-7400 1575) $PN AR48
J 0
(-7390 1585);
DISPLAY 0.489362 (-7390 1585);
PAINT MONO (-7390 1585);
FORCEPROP 0 LASTPIN (-7400 1525) $PN AR50
J 0
(-7390 1535);
DISPLAY 0.489362 (-7390 1535);
PAINT MONO (-7390 1535);
FORCEPROP 0 LASTPIN (-7400 1475) $PN AT24
J 0
(-7390 1485);
DISPLAY 0.489362 (-7390 1485);
PAINT MONO (-7390 1485);
FORCEPROP 0 LASTPIN (-7400 1425) $PN AT26
J 0
(-7390 1435);
DISPLAY 0.489362 (-7390 1435);
PAINT MONO (-7390 1435);
FORCEPROP 0 LASTPIN (-7400 1375) $PN AT28
J 0
(-7390 1385);
DISPLAY 0.489362 (-7390 1385);
PAINT MONO (-7390 1385);
FORCEPROP 0 LASTPIN (-7400 1325) $PN AT30
J 0
(-7390 1335);
DISPLAY 0.489362 (-7390 1335);
PAINT MONO (-7390 1335);
FORCEPROP 0 LASTPIN (-7400 1275) $PN AT32
J 0
(-7390 1285);
DISPLAY 0.489362 (-7390 1285);
PAINT MONO (-7390 1285);
FORCEPROP 0 LASTPIN (-7400 1225) $PN AT34
J 0
(-7390 1235);
DISPLAY 0.489362 (-7390 1235);
PAINT MONO (-7390 1235);
FORCEPROP 0 LASTPIN (-7400 1175) $PN AT36
J 0
(-7390 1185);
DISPLAY 0.489362 (-7390 1185);
PAINT MONO (-7390 1185);
FORCEPROP 0 LASTPIN (-7400 1125) $PN AT39
J 0
(-7390 1135);
DISPLAY 0.489362 (-7390 1135);
PAINT MONO (-7390 1135);
FORCEPROP 0 LASTPIN (-7400 1075) $PN AT41
J 0
(-7390 1085);
DISPLAY 0.489362 (-7390 1085);
PAINT MONO (-7390 1085);
FORCEPROP 0 LASTPIN (-7400 1025) $PN AT43
J 0
(-7390 1035);
DISPLAY 0.489362 (-7390 1035);
PAINT MONO (-7390 1035);
FORCEPROP 0 LASTPIN (-7400 975) $PN AT45
J 0
(-7390 985);
DISPLAY 0.489362 (-7390 985);
PAINT MONO (-7390 985);
FORCEPROP 0 LASTPIN (-7400 925) $PN AT47
J 0
(-7390 935);
DISPLAY 0.489362 (-7390 935);
PAINT MONO (-7390 935);
FORCEPROP 0 LASTPIN (-7400 875) $PN AT49
J 0
(-7390 885);
DISPLAY 0.489362 (-7390 885);
PAINT MONO (-7390 885);
FORCEPROP 0 LASTPIN (-7400 575) $PN AU25
J 0
(-7390 585);
DISPLAY 0.489362 (-7390 585);
PAINT MONO (-7390 585);
FORCEPROP 0 LASTPIN (-7400 825) $PN AU29
J 0
(-7390 835);
DISPLAY 0.489362 (-7390 835);
PAINT MONO (-7390 835);
FORCEPROP 0 LASTPIN (-7400 525) $PN AU33
J 0
(-7390 535);
DISPLAY 0.489362 (-7390 535);
PAINT MONO (-7390 535);
FORCEPROP 0 LASTPIN (-7400 775) $PN AU42
J 0
(-7390 785);
DISPLAY 0.489362 (-7390 785);
PAINT MONO (-7390 785);
FORCEPROP 0 LASTPIN (-7400 675) $PN AU44
J 0
(-7390 685);
DISPLAY 0.489362 (-7390 685);
PAINT MONO (-7390 685);
FORCEPROP 0 LASTPIN (-7400 725) $PN AU46
J 0
(-7390 735);
DISPLAY 0.489362 (-7390 735);
PAINT MONO (-7390 735);
FORCEPROP 0 LASTPIN (-7400 625) $PN AU48
J 0
(-7390 635);
DISPLAY 0.489362 (-7390 635);
PAINT MONO (-7390 635);
FORCEPROP 0 LASTPIN (-8700 6325) $PN B19
J 2
(-8710 6335);
DISPLAY 0.489362 (-8710 6335);
PAINT MONO (-8710 6335);
FORCEPROP 0 LASTPIN (-8700 6275) $PN B20
J 2
(-8710 6285);
DISPLAY 0.489362 (-8710 6285);
PAINT MONO (-8710 6285);
FORCEPROP 0 LASTPIN (-8700 6225) $PN B22
J 2
(-8710 6235);
DISPLAY 0.489362 (-8710 6235);
PAINT MONO (-8710 6235);
FORCEPROP 0 LASTPIN (-8700 6175) $PN B23
J 2
(-8710 6185);
DISPLAY 0.489362 (-8710 6185);
PAINT MONO (-8710 6185);
FORCEPROP 0 LASTPIN (-8700 6125) $PN B25
J 2
(-8710 6135);
DISPLAY 0.489362 (-8710 6135);
PAINT MONO (-8710 6135);
FORCEPROP 0 LASTPIN (-8700 6075) $PN B26
J 2
(-8710 6085);
DISPLAY 0.489362 (-8710 6085);
PAINT MONO (-8710 6085);
FORCEPROP 0 LASTPIN (-8700 6025) $PN B28
J 2
(-8710 6035);
DISPLAY 0.489362 (-8710 6035);
PAINT MONO (-8710 6035);
FORCEPROP 0 LASTPIN (-8700 5975) $PN B29
J 2
(-8710 5985);
DISPLAY 0.489362 (-8710 5985);
PAINT MONO (-8710 5985);
FORCEPROP 0 LASTPIN (-8700 5925) $PN B31
J 2
(-8710 5935);
DISPLAY 0.489362 (-8710 5935);
PAINT MONO (-8710 5935);
FORCEPROP 0 LASTPIN (-8700 5875) $PN B32
J 2
(-8710 5885);
DISPLAY 0.489362 (-8710 5885);
PAINT MONO (-8710 5885);
FORCEPROP 0 LASTPIN (-8700 5825) $PN B34
J 2
(-8710 5835);
DISPLAY 0.489362 (-8710 5835);
PAINT MONO (-8710 5835);
FORCEPROP 0 LASTPIN (-8700 5775) $PN B35
J 2
(-8710 5785);
DISPLAY 0.489362 (-8710 5785);
PAINT MONO (-8710 5785);
FORCEPROP 0 LASTPIN (-8700 5725) $PN B41
J 2
(-8710 5735);
DISPLAY 0.489362 (-8710 5735);
PAINT MONO (-8710 5735);
FORCEPROP 0 LASTPIN (-8700 5675) $PN B42
J 2
(-8710 5685);
DISPLAY 0.489362 (-8710 5685);
PAINT MONO (-8710 5685);
FORCEPROP 0 LASTPIN (-8700 5625) $PN B44
J 2
(-8710 5635);
DISPLAY 0.489362 (-8710 5635);
PAINT MONO (-8710 5635);
FORCEPROP 0 LASTPIN (-8700 5575) $PN B45
J 2
(-8710 5585);
DISPLAY 0.489362 (-8710 5585);
PAINT MONO (-8710 5585);
FORCEPROP 0 LASTPIN (-8700 5525) $PN B47
J 2
(-8710 5535);
DISPLAY 0.489362 (-8710 5535);
PAINT MONO (-8710 5535);
FORCEPROP 0 LASTPIN (-8700 5475) $PN B48
J 2
(-8710 5485);
DISPLAY 0.489362 (-8710 5485);
PAINT MONO (-8710 5485);
FORCEPROP 0 LASTPIN (-8700 5425) $PN B50
J 2
(-8710 5435);
DISPLAY 0.489362 (-8710 5435);
PAINT MONO (-8710 5435);
FORCEPROP 0 LASTPIN (-8700 5375) $PN B51
J 2
(-8710 5385);
DISPLAY 0.489362 (-8710 5385);
PAINT MONO (-8710 5385);
FORCEPROP 0 LASTPIN (-8700 5325) $PN B53
J 2
(-8710 5335);
DISPLAY 0.489362 (-8710 5335);
PAINT MONO (-8710 5335);
FORCEPROP 0 LASTPIN (-8700 5275) $PN B54
J 2
(-8710 5285);
DISPLAY 0.489362 (-8710 5285);
PAINT MONO (-8710 5285);
FORCEPROP 0 LASTPIN (-8700 5225) $PN B56
J 2
(-8710 5235);
DISPLAY 0.489362 (-8710 5235);
PAINT MONO (-8710 5235);
FORCEPROP 0 LASTPIN (-8700 5175) $PN B57
J 2
(-8710 5185);
DISPLAY 0.489362 (-8710 5185);
PAINT MONO (-8710 5185);
FORCEPROP 0 LASTPIN (-8700 5125) $PN C20
J 2
(-8710 5135);
DISPLAY 0.489362 (-8710 5135);
PAINT MONO (-8710 5135);
FORCEPROP 0 LASTPIN (-8700 5075) $PN D55
J 2
(-8710 5085);
DISPLAY 0.489362 (-8710 5085);
PAINT MONO (-8710 5085);
FORCEPROP 0 LASTPIN (-8700 5025) $PN D56
J 2
(-8710 5035);
DISPLAY 0.489362 (-8710 5035);
PAINT MONO (-8710 5035);
FORCEPROP 0 LASTPIN (-8700 4975) $PN E22
J 2
(-8710 4985);
DISPLAY 0.489362 (-8710 4985);
PAINT MONO (-8710 4985);
FORCEPROP 0 LASTPIN (-8700 4925) $PN E25
J 2
(-8710 4935);
DISPLAY 0.489362 (-8710 4935);
PAINT MONO (-8710 4935);
FORCEPROP 0 LASTPIN (-8700 4875) $PN E28
J 2
(-8710 4885);
DISPLAY 0.489362 (-8710 4885);
PAINT MONO (-8710 4885);
FORCEPROP 0 LASTPIN (-8700 4825) $PN E31
J 2
(-8710 4835);
DISPLAY 0.489362 (-8710 4835);
PAINT MONO (-8710 4835);
FORCEPROP 0 LASTPIN (-8700 4775) $PN E34
J 2
(-8710 4785);
DISPLAY 0.489362 (-8710 4785);
PAINT MONO (-8710 4785);
FORCEPROP 0 LASTPIN (-8700 4725) $PN E35
J 2
(-8710 4735);
DISPLAY 0.489362 (-8710 4735);
PAINT MONO (-8710 4735);
FORCEPROP 0 LASTPIN (-8700 4675) $PN E42
J 2
(-8710 4685);
DISPLAY 0.489362 (-8710 4685);
PAINT MONO (-8710 4685);
FORCEPROP 0 LASTPIN (-8700 4625) $PN E45
J 2
(-8710 4635);
DISPLAY 0.489362 (-8710 4635);
PAINT MONO (-8710 4635);
FORCEPROP 0 LASTPIN (-8700 4575) $PN E48
J 2
(-8710 4585);
DISPLAY 0.489362 (-8710 4585);
PAINT MONO (-8710 4585);
FORCEPROP 0 LASTPIN (-8700 4525) $PN E51
J 2
(-8710 4535);
DISPLAY 0.489362 (-8710 4535);
PAINT MONO (-8710 4535);
FORCEPROP 0 LASTPIN (-8700 4475) $PN E54
J 2
(-8710 4485);
DISPLAY 0.489362 (-8710 4485);
PAINT MONO (-8710 4485);
FORCEPROP 0 LASTPIN (-8700 4425) $PN F22
J 2
(-8710 4435);
DISPLAY 0.489362 (-8710 4435);
PAINT MONO (-8710 4435);
FORCEPROP 0 LASTPIN (-8700 4375) $PN F25
J 2
(-8710 4385);
DISPLAY 0.489362 (-8710 4385);
PAINT MONO (-8710 4385);
FORCEPROP 0 LASTPIN (-8700 4325) $PN F28
J 2
(-8710 4335);
DISPLAY 0.489362 (-8710 4335);
PAINT MONO (-8710 4335);
FORCEPROP 0 LASTPIN (-8700 4275) $PN F31
J 2
(-8710 4285);
DISPLAY 0.489362 (-8710 4285);
PAINT MONO (-8710 4285);
FORCEPROP 0 LASTPIN (-8700 4225) $PN F34
J 2
(-8710 4235);
DISPLAY 0.489362 (-8710 4235);
PAINT MONO (-8710 4235);
FORCEPROP 0 LASTPIN (-8700 4175) $PN F42
J 2
(-8710 4185);
DISPLAY 0.489362 (-8710 4185);
PAINT MONO (-8710 4185);
FORCEPROP 0 LASTPIN (-8700 4125) $PN F45
J 2
(-8710 4135);
DISPLAY 0.489362 (-8710 4135);
PAINT MONO (-8710 4135);
FORCEPROP 0 LASTPIN (-8700 4075) $PN F48
J 2
(-8710 4085);
DISPLAY 0.489362 (-8710 4085);
PAINT MONO (-8710 4085);
FORCEPROP 0 LASTPIN (-8700 4025) $PN F51
J 2
(-8710 4035);
DISPLAY 0.489362 (-8710 4035);
PAINT MONO (-8710 4035);
FORCEPROP 0 LASTPIN (-8700 3975) $PN F54
J 2
(-8710 3985);
DISPLAY 0.489362 (-8710 3985);
PAINT MONO (-8710 3985);
FORCEPROP 0 LASTPIN (-8700 3925) $PN G35
J 2
(-8710 3935);
DISPLAY 0.489362 (-8710 3935);
PAINT MONO (-8710 3935);
FORCEPROP 0 LASTPIN (-8700 3875) $PN G36
J 2
(-8710 3885);
DISPLAY 0.489362 (-8710 3885);
PAINT MONO (-8710 3885);
FORCEPROP 0 LASTPIN (-8700 3825) $PN G40
J 2
(-8710 3835);
DISPLAY 0.489362 (-8710 3835);
PAINT MONO (-8710 3835);
FORCEPROP 0 LASTPIN (-8700 3775) $PN G41
J 2
(-8710 3785);
DISPLAY 0.489362 (-8710 3785);
PAINT MONO (-8710 3785);
FORCEPROP 0 LASTPIN (-8700 3725) $PN H23
J 2
(-8710 3735);
DISPLAY 0.489362 (-8710 3735);
PAINT MONO (-8710 3735);
FORCEPROP 0 LASTPIN (-8700 3675) $PN H24
J 2
(-8710 3685);
DISPLAY 0.489362 (-8710 3685);
PAINT MONO (-8710 3685);
FORCEPROP 0 LASTPIN (-8700 3625) $PN H26
J 2
(-8710 3635);
DISPLAY 0.489362 (-8710 3635);
PAINT MONO (-8710 3635);
FORCEPROP 0 LASTPIN (-8700 3575) $PN H27
J 2
(-8710 3585);
DISPLAY 0.489362 (-8710 3585);
PAINT MONO (-8710 3585);
FORCEPROP 0 LASTPIN (-8700 3525) $PN H29
J 2
(-8710 3535);
DISPLAY 0.489362 (-8710 3535);
PAINT MONO (-8710 3535);
FORCEPROP 0 LASTPIN (-8700 3475) $PN H30
J 2
(-8710 3485);
DISPLAY 0.489362 (-8710 3485);
PAINT MONO (-8710 3485);
FORCEPROP 0 LASTPIN (-8700 3425) $PN H32
J 2
(-8710 3435);
DISPLAY 0.489362 (-8710 3435);
PAINT MONO (-8710 3435);
FORCEPROP 0 LASTPIN (-8700 3375) $PN H33
J 2
(-8710 3385);
DISPLAY 0.489362 (-8710 3385);
PAINT MONO (-8710 3385);
FORCEPROP 0 LASTPIN (-8700 3325) $PN H43
J 2
(-8710 3335);
DISPLAY 0.489362 (-8710 3335);
PAINT MONO (-8710 3335);
FORCEPROP 0 LASTPIN (-8700 3275) $PN H44
J 2
(-8710 3285);
DISPLAY 0.489362 (-8710 3285);
PAINT MONO (-8710 3285);
FORCEPROP 0 LASTPIN (-8700 3225) $PN H46
J 2
(-8710 3235);
DISPLAY 0.489362 (-8710 3235);
PAINT MONO (-8710 3235);
FORCEPROP 0 LASTPIN (-8700 3175) $PN H47
J 2
(-8710 3185);
DISPLAY 0.489362 (-8710 3185);
PAINT MONO (-8710 3185);
FORCEPROP 0 LASTPIN (-8700 3125) $PN H49
J 2
(-8710 3135);
DISPLAY 0.489362 (-8710 3135);
PAINT MONO (-8710 3135);
FORCEPROP 0 LASTPIN (-8700 3075) $PN H50
J 2
(-8710 3085);
DISPLAY 0.489362 (-8710 3085);
PAINT MONO (-8710 3085);
FORCEPROP 0 LASTPIN (-8700 3025) $PN H52
J 2
(-8710 3035);
DISPLAY 0.489362 (-8710 3035);
PAINT MONO (-8710 3035);
FORCEPROP 0 LASTPIN (-8700 2975) $PN H53
J 2
(-8710 2985);
DISPLAY 0.489362 (-8710 2985);
PAINT MONO (-8710 2985);
FORCEPROP 0 LASTPIN (-8700 2925) $PN J35
J 2
(-8710 2935);
DISPLAY 0.489362 (-8710 2935);
PAINT MONO (-8710 2935);
FORCEPROP 0 LASTPIN (-8700 2875) $PN J36
J 2
(-8710 2885);
DISPLAY 0.489362 (-8710 2885);
PAINT MONO (-8710 2885);
FORCEPROP 0 LASTPIN (-8700 2825) $PN J40
J 2
(-8710 2835);
DISPLAY 0.489362 (-8710 2835);
PAINT MONO (-8710 2835);
FORCEPROP 0 LASTPIN (-8700 2775) $PN J41
J 2
(-8710 2785);
DISPLAY 0.489362 (-8710 2785);
PAINT MONO (-8710 2785);
FORCEPROP 0 LASTPIN (-8700 2725) $PN M23
J 2
(-8710 2735);
DISPLAY 0.489362 (-8710 2735);
PAINT MONO (-8710 2735);
FORCEPROP 0 LASTPIN (-8700 2675) $PN M24
J 2
(-8710 2685);
DISPLAY 0.489362 (-8710 2685);
PAINT MONO (-8710 2685);
FORCEPROP 0 LASTPIN (-8700 2625) $PN M26
J 2
(-8710 2635);
DISPLAY 0.489362 (-8710 2635);
PAINT MONO (-8710 2635);
FORCEPROP 0 LASTPIN (-8700 2575) $PN M27
J 2
(-8710 2585);
DISPLAY 0.489362 (-8710 2585);
PAINT MONO (-8710 2585);
FORCEPROP 0 LASTPIN (-8700 2525) $PN M29
J 2
(-8710 2535);
DISPLAY 0.489362 (-8710 2535);
PAINT MONO (-8710 2535);
FORCEPROP 0 LASTPIN (-8700 2475) $PN M30
J 2
(-8710 2485);
DISPLAY 0.489362 (-8710 2485);
PAINT MONO (-8710 2485);
FORCEPROP 0 LASTPIN (-8700 2425) $PN M32
J 2
(-8710 2435);
DISPLAY 0.489362 (-8710 2435);
PAINT MONO (-8710 2435);
FORCEPROP 0 LASTPIN (-8700 2375) $PN M33
J 2
(-8710 2385);
DISPLAY 0.489362 (-8710 2385);
PAINT MONO (-8710 2385);
FORCEPROP 0 LASTPIN (-8700 2325) $PN M43
J 2
(-8710 2335);
DISPLAY 0.489362 (-8710 2335);
PAINT MONO (-8710 2335);
FORCEPROP 0 LASTPIN (-8700 2275) $PN M44
J 2
(-8710 2285);
DISPLAY 0.489362 (-8710 2285);
PAINT MONO (-8710 2285);
FORCEPROP 0 LASTPIN (-8700 2225) $PN M46
J 2
(-8710 2235);
DISPLAY 0.489362 (-8710 2235);
PAINT MONO (-8710 2235);
FORCEPROP 0 LASTPIN (-8700 2175) $PN M47
J 2
(-8710 2185);
DISPLAY 0.489362 (-8710 2185);
PAINT MONO (-8710 2185);
FORCEPROP 0 LASTPIN (-8700 2125) $PN M49
J 2
(-8710 2135);
DISPLAY 0.489362 (-8710 2135);
PAINT MONO (-8710 2135);
FORCEPROP 0 LASTPIN (-8700 2075) $PN M50
J 2
(-8710 2085);
DISPLAY 0.489362 (-8710 2085);
PAINT MONO (-8710 2085);
FORCEPROP 0 LASTPIN (-8700 2025) $PN M52
J 2
(-8710 2035);
DISPLAY 0.489362 (-8710 2035);
PAINT MONO (-8710 2035);
FORCEPROP 0 LASTPIN (-8700 1975) $PN M53
J 2
(-8710 1985);
DISPLAY 0.489362 (-8710 1985);
PAINT MONO (-8710 1985);
FORCEPROP 0 LASTPIN (-8700 1925) $PN N35
J 2
(-8710 1935);
DISPLAY 0.489362 (-8710 1935);
PAINT MONO (-8710 1935);
FORCEPROP 0 LASTPIN (-8700 1875) $PN N36
J 2
(-8710 1885);
DISPLAY 0.489362 (-8710 1885);
PAINT MONO (-8710 1885);
FORCEPROP 0 LASTPIN (-8700 1825) $PN N40
J 2
(-8710 1835);
DISPLAY 0.489362 (-8710 1835);
PAINT MONO (-8710 1835);
FORCEPROP 0 LASTPIN (-8700 1775) $PN N41
J 2
(-8710 1785);
DISPLAY 0.489362 (-8710 1785);
PAINT MONO (-8710 1785);
FORCEPROP 0 LASTPIN (-8700 1725) $PN T23
J 2
(-8710 1735);
DISPLAY 0.489362 (-8710 1735);
PAINT MONO (-8710 1735);
FORCEPROP 0 LASTPIN (-8700 1675) $PN T24
J 2
(-8710 1685);
DISPLAY 0.489362 (-8710 1685);
PAINT MONO (-8710 1685);
FORCEPROP 0 LASTPIN (-8700 1625) $PN T26
J 2
(-8710 1635);
DISPLAY 0.489362 (-8710 1635);
PAINT MONO (-8710 1635);
FORCEPROP 0 LASTPIN (-8700 1575) $PN T27
J 2
(-8710 1585);
DISPLAY 0.489362 (-8710 1585);
PAINT MONO (-8710 1585);
FORCEPROP 0 LASTPIN (-8700 1525) $PN T29
J 2
(-8710 1535);
DISPLAY 0.489362 (-8710 1535);
PAINT MONO (-8710 1535);
FORCEPROP 0 LASTPIN (-8700 1475) $PN T30
J 2
(-8710 1485);
DISPLAY 0.489362 (-8710 1485);
PAINT MONO (-8710 1485);
FORCEPROP 0 LASTPIN (-8700 1425) $PN T32
J 2
(-8710 1435);
DISPLAY 0.489362 (-8710 1435);
PAINT MONO (-8710 1435);
FORCEPROP 0 LASTPIN (-8700 1375) $PN T33
J 2
(-8710 1385);
DISPLAY 0.489362 (-8710 1385);
PAINT MONO (-8710 1385);
FORCEPROP 0 LASTPIN (-8700 1325) $PN T43
J 2
(-8710 1335);
DISPLAY 0.489362 (-8710 1335);
PAINT MONO (-8710 1335);
FORCEPROP 0 LASTPIN (-8700 1275) $PN T44
J 2
(-8710 1285);
DISPLAY 0.489362 (-8710 1285);
PAINT MONO (-8710 1285);
FORCEPROP 0 LASTPIN (-8700 1225) $PN T46
J 2
(-8710 1235);
DISPLAY 0.489362 (-8710 1235);
PAINT MONO (-8710 1235);
FORCEPROP 0 LASTPIN (-8700 1175) $PN T47
J 2
(-8710 1185);
DISPLAY 0.489362 (-8710 1185);
PAINT MONO (-8710 1185);
FORCEPROP 0 LASTPIN (-8700 1125) $PN T49
J 2
(-8710 1135);
DISPLAY 0.489362 (-8710 1135);
PAINT MONO (-8710 1135);
FORCEPROP 0 LASTPIN (-8700 1075) $PN T50
J 2
(-8710 1085);
DISPLAY 0.489362 (-8710 1085);
PAINT MONO (-8710 1085);
FORCEPROP 0 LASTPIN (-8700 1025) $PN T52
J 2
(-8710 1035);
DISPLAY 0.489362 (-8710 1035);
PAINT MONO (-8710 1035);
FORCEPROP 0 LASTPIN (-8700 975) $PN T53
J 2
(-8710 985);
DISPLAY 0.489362 (-8710 985);
PAINT MONO (-8710 985);
FORCEPROP 0 LASTPIN (-8700 925) $PN U35
J 2
(-8710 935);
DISPLAY 0.489362 (-8710 935);
PAINT MONO (-8710 935);
FORCEPROP 0 LASTPIN (-8700 875) $PN U36
J 2
(-8710 885);
DISPLAY 0.489362 (-8710 885);
PAINT MONO (-8710 885);
FORCEPROP 0 LASTPIN (-8700 825) $PN U40
J 2
(-8710 835);
DISPLAY 0.489362 (-8710 835);
PAINT MONO (-8710 835);
FORCEPROP 0 LASTPIN (-8700 775) $PN U41
J 2
(-8710 785);
DISPLAY 0.489362 (-8710 785);
PAINT MONO (-8710 785);
FORCEPROP 0 LASTPIN (-8700 725) $PN W29
J 2
(-8710 735);
DISPLAY 0.489362 (-8710 735);
PAINT MONO (-8710 735);
FORCEPROP 0 LASTPIN (-8700 675) $PN W30
J 2
(-8710 685);
DISPLAY 0.489362 (-8710 685);
PAINT MONO (-8710 685);
FORCEPROP 0 LASTPIN (-8700 625) $PN W32
J 2
(-8710 635);
DISPLAY 0.489362 (-8710 635);
PAINT MONO (-8710 635);
FORCEPROP 0 LASTPIN (-8700 575) $PN W33
J 2
(-8710 585);
DISPLAY 0.489362 (-8710 585);
PAINT MONO (-8710 585);
FORCEPROP 0 LASTPIN (-7400 6325) $PN W43
J 0
(-7390 6335);
DISPLAY 0.489362 (-7390 6335);
PAINT MONO (-7390 6335);
FORCEPROP 0 LASTPIN (-7400 6275) $PN W44
J 0
(-7390 6285);
DISPLAY 0.489362 (-7390 6285);
PAINT MONO (-7390 6285);
FORCEPROP 0 LASTPIN (-7400 6225) $PN W46
J 0
(-7390 6235);
DISPLAY 0.489362 (-7390 6235);
PAINT MONO (-7390 6235);
FORCEPROP 0 LASTPIN (-7400 6175) $PN W47
J 0
(-7390 6185);
DISPLAY 0.489362 (-7390 6185);
PAINT MONO (-7390 6185);
FORCEPROP 0 LASTPIN (-7400 6125) $PN Y35
J 0
(-7390 6135);
DISPLAY 0.489362 (-7390 6135);
PAINT MONO (-7390 6135);
FORCEPROP 0 LASTPIN (-7400 6075) $PN Y36
J 0
(-7390 6085);
DISPLAY 0.489362 (-7390 6085);
PAINT MONO (-7390 6085);
FORCEPROP 0 LASTPIN (-7400 6025) $PN Y40
J 0
(-7390 6035);
DISPLAY 0.489362 (-7390 6035);
PAINT MONO (-7390 6035);
FORCEPROP 0 LASTPIN (-7400 5975) $PN Y41
J 0
(-7390 5985);
DISPLAY 0.489362 (-7390 5985);
PAINT MONO (-7390 5985);
FORCEPROP 2 LAST PART_TYPE SMLF
J 0
(-8550 6700);
DISPLAY 1.021277 (-8550 6700);
FORCEPROP 1 LAST MATERIAL IO
J 0
(-8545 6495);
DISPLAY 0.489362 (-8545 6495);
PAINT SKYBLUE (-8545 6495);
FORCEPROP 2 LAST VALUE SOCKET6096_13568-001
J 0
(-8550 6550);
DISPLAY 0.489362 (-8550 6550);
PAINT SKYBLUE (-8550 6550);
FORCEPROP 1 LAST PART_NUMBER DGA^6000030
J 0
(-8550 6650);
DISPLAY 0.489362 (-8550 6650);
PAINT SKYBLUE (-8550 6650);
FORCEPROP 2 LAST CDS_LIB pure_quanta
J 0
(-8050 3325);
DISPLAY INVISIBLE (-8050 3325);
FORCEPROP 1 LAST CDS_LMAN_SYM_OUTLINE -500,3150,500,-3150
J 0
(-8050 3325);
DISPLAY 0.468085 (-8050 3325);
PAINT GREEN (-8050 3325);
DISPLAY INVISIBLE (-8050 3325);
FORCEPROP 1 LAST NEEDS_NO_SIZE TRUE
J 0
(-8050 3325);
DISPLAY 0.723404 (-8050 3325);
PAINT GREEN (-8050 3325);
DISPLAY INVISIBLE (-8050 3325);
FORCEPROP 1 LAST PATH I42
J 0
(-8050 3325);
DISPLAY 0.723404 (-8050 3325);
PAINT GREEN (-8050 3325);
DISPLAY INVISIBLE (-8050 3325);
FORCEADD VCC_CORE..1
(-7250 6575);
FORCEPROP 3 LASTPIN (-7250 6525) SIG_NAME PVDDCR_CPU0_P0\g
J 0
(-7240 6535);
DISPLAY 0.659574 (-7240 6535);
PAINT MONO (-7240 6535);
DISPLAY INVISIBLE (-7240 6535);
FORCEPROP 1 LAST HDL_POWER PVDDCR_CPU0_P0
J 1
(-7250 6625);
DISPLAY 0.489362 (-7250 6625);
PAINT GREEN (-7250 6625);
FORCEPROP 2 LAST CDS_LIB pure_quanta_power
J 0
(-7250 6575);
DISPLAY INVISIBLE (-7250 6575);
FORCEPROP 1 LAST PATH I43
J 0
(-7200 6600);
DISPLAY 0.872340 (-7200 6600);
PAINT AQUA (-7200 6600);
DISPLAY INVISIBLE (-7200 6600);
FORCEADD GENOA_SP5..25
(-6075 3350);
FORCEPROP 1 LAST LOCATION U25
J 0
(-6575 6650);
DISPLAY 0.489362 (-6575 6650);
PAINT SKYBLUE (-6575 6650);
FORCEPROP 0 LAST $SEC 25
J 0
(-6550 6900);
DISPLAY 0.680851 (-6550 6900);
PAINT MONO (-6550 6900);
DISPLAY INVISIBLE (-6550 6900);
FORCEPROP 0 LAST CDS_SEC 25
J 0
(-6950 6575);
DISPLAY 1.021277 (-6950 6575);
DISPLAY INVISIBLE (-6950 6575);
FORCEPROP 0 LASTPIN (-5425 500) $PN BN27
J 0
(-5415 510);
DISPLAY 0.489362 (-5415 510);
PAINT MONO (-5415 510);
FORCEPROP 0 LASTPIN (-6725 6100) $PN BN31
J 2
(-6735 6110);
DISPLAY 0.489362 (-6735 6110);
PAINT MONO (-6735 6110);
FORCEPROP 0 LASTPIN (-5425 450) $PN BN35
J 0
(-5415 460);
DISPLAY 0.489362 (-5415 460);
PAINT MONO (-5415 460);
FORCEPROP 0 LASTPIN (-6725 6050) $PN BN42
J 2
(-6735 6060);
DISPLAY 0.489362 (-6735 6060);
PAINT MONO (-6735 6060);
FORCEPROP 0 LASTPIN (-5425 400) $PN BN46
J 0
(-5415 410);
DISPLAY 0.489362 (-5415 410);
PAINT MONO (-5415 410);
FORCEPROP 0 LASTPIN (-6725 6000) $PN BN50
J 2
(-6735 6010);
DISPLAY 0.489362 (-6735 6010);
PAINT MONO (-6735 6010);
FORCEPROP 0 LASTPIN (-5425 350) $PN BP24
J 0
(-5415 360);
DISPLAY 0.489362 (-5415 360);
PAINT MONO (-5415 360);
FORCEPROP 0 LASTPIN (-6725 5950) $PN BP26
J 2
(-6735 5960);
DISPLAY 0.489362 (-6735 5960);
PAINT MONO (-6735 5960);
FORCEPROP 0 LASTPIN (-5425 300) $PN BP28
J 0
(-5415 310);
DISPLAY 0.489362 (-5415 310);
PAINT MONO (-5415 310);
FORCEPROP 0 LASTPIN (-6725 5900) $PN BP30
J 2
(-6735 5910);
DISPLAY 0.489362 (-6735 5910);
PAINT MONO (-6735 5910);
FORCEPROP 0 LASTPIN (-5425 250) $PN BP32
J 0
(-5415 260);
DISPLAY 0.489362 (-5415 260);
PAINT MONO (-5415 260);
FORCEPROP 0 LASTPIN (-6725 5850) $PN BP34
J 2
(-6735 5860);
DISPLAY 0.489362 (-6735 5860);
PAINT MONO (-6735 5860);
FORCEPROP 0 LASTPIN (-6725 5800) $PN BP36
J 2
(-6735 5810);
DISPLAY 0.489362 (-6735 5810);
PAINT MONO (-6735 5810);
FORCEPROP 0 LASTPIN (-6725 5750) $PN BP39
J 2
(-6735 5760);
DISPLAY 0.489362 (-6735 5760);
PAINT MONO (-6735 5760);
FORCEPROP 0 LASTPIN (-6725 5700) $PN BP41
J 2
(-6735 5710);
DISPLAY 0.489362 (-6735 5710);
PAINT MONO (-6735 5710);
FORCEPROP 0 LASTPIN (-6725 5650) $PN BP43
J 2
(-6735 5660);
DISPLAY 0.489362 (-6735 5660);
PAINT MONO (-6735 5660);
FORCEPROP 0 LASTPIN (-6725 5600) $PN BP45
J 2
(-6735 5610);
DISPLAY 0.489362 (-6735 5610);
PAINT MONO (-6735 5610);
FORCEPROP 0 LASTPIN (-6725 5550) $PN BP47
J 2
(-6735 5560);
DISPLAY 0.489362 (-6735 5560);
PAINT MONO (-6735 5560);
FORCEPROP 0 LASTPIN (-6725 5500) $PN BP49
J 2
(-6735 5510);
DISPLAY 0.489362 (-6735 5510);
PAINT MONO (-6735 5510);
FORCEPROP 0 LASTPIN (-6725 5450) $PN BR23
J 2
(-6735 5460);
DISPLAY 0.489362 (-6735 5460);
PAINT MONO (-6735 5460);
FORCEPROP 0 LASTPIN (-6725 5400) $PN BR25
J 2
(-6735 5410);
DISPLAY 0.489362 (-6735 5410);
PAINT MONO (-6735 5410);
FORCEPROP 0 LASTPIN (-6725 5350) $PN BR27
J 2
(-6735 5360);
DISPLAY 0.489362 (-6735 5360);
PAINT MONO (-6735 5360);
FORCEPROP 0 LASTPIN (-6725 5300) $PN BR29
J 2
(-6735 5310);
DISPLAY 0.489362 (-6735 5310);
PAINT MONO (-6735 5310);
FORCEPROP 0 LASTPIN (-6725 5250) $PN BR31
J 2
(-6735 5260);
DISPLAY 0.489362 (-6735 5260);
PAINT MONO (-6735 5260);
FORCEPROP 0 LASTPIN (-6725 5200) $PN BR33
J 2
(-6735 5210);
DISPLAY 0.489362 (-6735 5210);
PAINT MONO (-6735 5210);
FORCEPROP 0 LASTPIN (-6725 5150) $PN BR35
J 2
(-6735 5160);
DISPLAY 0.489362 (-6735 5160);
PAINT MONO (-6735 5160);
FORCEPROP 0 LASTPIN (-6725 5100) $PN BR40
J 2
(-6735 5110);
DISPLAY 0.489362 (-6735 5110);
PAINT MONO (-6735 5110);
FORCEPROP 0 LASTPIN (-6725 5050) $PN BR42
J 2
(-6735 5060);
DISPLAY 0.489362 (-6735 5060);
PAINT MONO (-6735 5060);
FORCEPROP 0 LASTPIN (-6725 5000) $PN BR44
J 2
(-6735 5010);
DISPLAY 0.489362 (-6735 5010);
PAINT MONO (-6735 5010);
FORCEPROP 0 LASTPIN (-6725 4950) $PN BR46
J 2
(-6735 4960);
DISPLAY 0.489362 (-6735 4960);
PAINT MONO (-6735 4960);
FORCEPROP 0 LASTPIN (-6725 4900) $PN BR48
J 2
(-6735 4910);
DISPLAY 0.489362 (-6735 4910);
PAINT MONO (-6735 4910);
FORCEPROP 0 LASTPIN (-6725 4850) $PN BR50
J 2
(-6735 4860);
DISPLAY 0.489362 (-6735 4860);
PAINT MONO (-6735 4860);
FORCEPROP 0 LASTPIN (-6725 4800) $PN BR52
J 2
(-6735 4810);
DISPLAY 0.489362 (-6735 4810);
PAINT MONO (-6735 4810);
FORCEPROP 0 LASTPIN (-6725 4750) $PN BT23
J 2
(-6735 4760);
DISPLAY 0.489362 (-6735 4760);
PAINT MONO (-6735 4760);
FORCEPROP 0 LASTPIN (-6725 4700) $PN BT24
J 2
(-6735 4710);
DISPLAY 0.489362 (-6735 4710);
PAINT MONO (-6735 4710);
FORCEPROP 0 LASTPIN (-6725 4650) $PN BT26
J 2
(-6735 4660);
DISPLAY 0.489362 (-6735 4660);
PAINT MONO (-6735 4660);
FORCEPROP 0 LASTPIN (-6725 4600) $PN BT27
J 2
(-6735 4610);
DISPLAY 0.489362 (-6735 4610);
PAINT MONO (-6735 4610);
FORCEPROP 0 LASTPIN (-6725 4550) $PN BT29
J 2
(-6735 4560);
DISPLAY 0.489362 (-6735 4560);
PAINT MONO (-6735 4560);
FORCEPROP 0 LASTPIN (-6725 4500) $PN BT30
J 2
(-6735 4510);
DISPLAY 0.489362 (-6735 4510);
PAINT MONO (-6735 4510);
FORCEPROP 0 LASTPIN (-6725 4450) $PN BT32
J 2
(-6735 4460);
DISPLAY 0.489362 (-6735 4460);
PAINT MONO (-6735 4460);
FORCEPROP 0 LASTPIN (-6725 4400) $PN BT33
J 2
(-6735 4410);
DISPLAY 0.489362 (-6735 4410);
PAINT MONO (-6735 4410);
FORCEPROP 0 LASTPIN (-6725 4350) $PN BT43
J 2
(-6735 4360);
DISPLAY 0.489362 (-6735 4360);
PAINT MONO (-6735 4360);
FORCEPROP 0 LASTPIN (-6725 4300) $PN BT44
J 2
(-6735 4310);
DISPLAY 0.489362 (-6735 4310);
PAINT MONO (-6735 4310);
FORCEPROP 0 LASTPIN (-6725 4250) $PN BT46
J 2
(-6735 4260);
DISPLAY 0.489362 (-6735 4260);
PAINT MONO (-6735 4260);
FORCEPROP 0 LASTPIN (-6725 4200) $PN BT47
J 2
(-6735 4210);
DISPLAY 0.489362 (-6735 4210);
PAINT MONO (-6735 4210);
FORCEPROP 0 LASTPIN (-6725 4150) $PN BT49
J 2
(-6735 4160);
DISPLAY 0.489362 (-6735 4160);
PAINT MONO (-6735 4160);
FORCEPROP 0 LASTPIN (-6725 4100) $PN BT50
J 2
(-6735 4110);
DISPLAY 0.489362 (-6735 4110);
PAINT MONO (-6735 4110);
FORCEPROP 0 LASTPIN (-6725 4050) $PN BT52
J 2
(-6735 4060);
DISPLAY 0.489362 (-6735 4060);
PAINT MONO (-6735 4060);
FORCEPROP 0 LASTPIN (-6725 4000) $PN BT53
J 2
(-6735 4010);
DISPLAY 0.489362 (-6735 4010);
PAINT MONO (-6735 4010);
FORCEPROP 0 LASTPIN (-6725 3950) $PN BW35
J 2
(-6735 3960);
DISPLAY 0.489362 (-6735 3960);
PAINT MONO (-6735 3960);
FORCEPROP 0 LASTPIN (-6725 3900) $PN BW36
J 2
(-6735 3910);
DISPLAY 0.489362 (-6735 3910);
PAINT MONO (-6735 3910);
FORCEPROP 0 LASTPIN (-6725 3850) $PN BW40
J 2
(-6735 3860);
DISPLAY 0.489362 (-6735 3860);
PAINT MONO (-6735 3860);
FORCEPROP 0 LASTPIN (-6725 3800) $PN BW41
J 2
(-6735 3810);
DISPLAY 0.489362 (-6735 3810);
PAINT MONO (-6735 3810);
FORCEPROP 0 LASTPIN (-6725 3750) $PN BY23
J 2
(-6735 3760);
DISPLAY 0.489362 (-6735 3760);
PAINT MONO (-6735 3760);
FORCEPROP 0 LASTPIN (-6725 3700) $PN BY24
J 2
(-6735 3710);
DISPLAY 0.489362 (-6735 3710);
PAINT MONO (-6735 3710);
FORCEPROP 0 LASTPIN (-6725 3650) $PN BY26
J 2
(-6735 3660);
DISPLAY 0.489362 (-6735 3660);
PAINT MONO (-6735 3660);
FORCEPROP 0 LASTPIN (-6725 3600) $PN BY27
J 2
(-6735 3610);
DISPLAY 0.489362 (-6735 3610);
PAINT MONO (-6735 3610);
FORCEPROP 0 LASTPIN (-6725 3550) $PN BY29
J 2
(-6735 3560);
DISPLAY 0.489362 (-6735 3560);
PAINT MONO (-6735 3560);
FORCEPROP 0 LASTPIN (-6725 3500) $PN BY30
J 2
(-6735 3510);
DISPLAY 0.489362 (-6735 3510);
PAINT MONO (-6735 3510);
FORCEPROP 0 LASTPIN (-6725 3450) $PN BY32
J 2
(-6735 3460);
DISPLAY 0.489362 (-6735 3460);
PAINT MONO (-6735 3460);
FORCEPROP 0 LASTPIN (-6725 3400) $PN BY33
J 2
(-6735 3410);
DISPLAY 0.489362 (-6735 3410);
PAINT MONO (-6735 3410);
FORCEPROP 0 LASTPIN (-6725 3350) $PN BY43
J 2
(-6735 3360);
DISPLAY 0.489362 (-6735 3360);
PAINT MONO (-6735 3360);
FORCEPROP 0 LASTPIN (-6725 3300) $PN BY44
J 2
(-6735 3310);
DISPLAY 0.489362 (-6735 3310);
PAINT MONO (-6735 3310);
FORCEPROP 0 LASTPIN (-6725 3250) $PN BY46
J 2
(-6735 3260);
DISPLAY 0.489362 (-6735 3260);
PAINT MONO (-6735 3260);
FORCEPROP 0 LASTPIN (-6725 3200) $PN BY47
J 2
(-6735 3210);
DISPLAY 0.489362 (-6735 3210);
PAINT MONO (-6735 3210);
FORCEPROP 0 LASTPIN (-6725 3150) $PN BY49
J 2
(-6735 3160);
DISPLAY 0.489362 (-6735 3160);
PAINT MONO (-6735 3160);
FORCEPROP 0 LASTPIN (-6725 3100) $PN BY50
J 2
(-6735 3110);
DISPLAY 0.489362 (-6735 3110);
PAINT MONO (-6735 3110);
FORCEPROP 0 LASTPIN (-6725 3050) $PN BY52
J 2
(-6735 3060);
DISPLAY 0.489362 (-6735 3060);
PAINT MONO (-6735 3060);
FORCEPROP 0 LASTPIN (-6725 3000) $PN BY53
J 2
(-6735 3010);
DISPLAY 0.489362 (-6735 3010);
PAINT MONO (-6735 3010);
FORCEPROP 0 LASTPIN (-6725 2950) $PN CC35
J 2
(-6735 2960);
DISPLAY 0.489362 (-6735 2960);
PAINT MONO (-6735 2960);
FORCEPROP 0 LASTPIN (-6725 2900) $PN CC36
J 2
(-6735 2910);
DISPLAY 0.489362 (-6735 2910);
PAINT MONO (-6735 2910);
FORCEPROP 0 LASTPIN (-6725 2850) $PN CC40
J 2
(-6735 2860);
DISPLAY 0.489362 (-6735 2860);
PAINT MONO (-6735 2860);
FORCEPROP 0 LASTPIN (-6725 2800) $PN CC41
J 2
(-6735 2810);
DISPLAY 0.489362 (-6735 2810);
PAINT MONO (-6735 2810);
FORCEPROP 0 LASTPIN (-6725 2750) $PN CD23
J 2
(-6735 2760);
DISPLAY 0.489362 (-6735 2760);
PAINT MONO (-6735 2760);
FORCEPROP 0 LASTPIN (-6725 2700) $PN CD24
J 2
(-6735 2710);
DISPLAY 0.489362 (-6735 2710);
PAINT MONO (-6735 2710);
FORCEPROP 0 LASTPIN (-6725 2650) $PN CD26
J 2
(-6735 2660);
DISPLAY 0.489362 (-6735 2660);
PAINT MONO (-6735 2660);
FORCEPROP 0 LASTPIN (-6725 2600) $PN CD27
J 2
(-6735 2610);
DISPLAY 0.489362 (-6735 2610);
PAINT MONO (-6735 2610);
FORCEPROP 0 LASTPIN (-6725 2550) $PN CD29
J 2
(-6735 2560);
DISPLAY 0.489362 (-6735 2560);
PAINT MONO (-6735 2560);
FORCEPROP 0 LASTPIN (-6725 2500) $PN CD30
J 2
(-6735 2510);
DISPLAY 0.489362 (-6735 2510);
PAINT MONO (-6735 2510);
FORCEPROP 0 LASTPIN (-6725 2450) $PN CD32
J 2
(-6735 2460);
DISPLAY 0.489362 (-6735 2460);
PAINT MONO (-6735 2460);
FORCEPROP 0 LASTPIN (-6725 2400) $PN CD33
J 2
(-6735 2410);
DISPLAY 0.489362 (-6735 2410);
PAINT MONO (-6735 2410);
FORCEPROP 0 LASTPIN (-6725 2350) $PN CD43
J 2
(-6735 2360);
DISPLAY 0.489362 (-6735 2360);
PAINT MONO (-6735 2360);
FORCEPROP 0 LASTPIN (-6725 2300) $PN CD44
J 2
(-6735 2310);
DISPLAY 0.489362 (-6735 2310);
PAINT MONO (-6735 2310);
FORCEPROP 0 LASTPIN (-6725 2250) $PN CD46
J 2
(-6735 2260);
DISPLAY 0.489362 (-6735 2260);
PAINT MONO (-6735 2260);
FORCEPROP 0 LASTPIN (-6725 2200) $PN CD47
J 2
(-6735 2210);
DISPLAY 0.489362 (-6735 2210);
PAINT MONO (-6735 2210);
FORCEPROP 0 LASTPIN (-6725 2150) $PN CD49
J 2
(-6735 2160);
DISPLAY 0.489362 (-6735 2160);
PAINT MONO (-6735 2160);
FORCEPROP 0 LASTPIN (-6725 2100) $PN CD50
J 2
(-6735 2110);
DISPLAY 0.489362 (-6735 2110);
PAINT MONO (-6735 2110);
FORCEPROP 0 LASTPIN (-6725 2050) $PN CD52
J 2
(-6735 2060);
DISPLAY 0.489362 (-6735 2060);
PAINT MONO (-6735 2060);
FORCEPROP 0 LASTPIN (-6725 2000) $PN CD53
J 2
(-6735 2010);
DISPLAY 0.489362 (-6735 2010);
PAINT MONO (-6735 2010);
FORCEPROP 0 LASTPIN (-6725 1950) $PN CG35
J 2
(-6735 1960);
DISPLAY 0.489362 (-6735 1960);
PAINT MONO (-6735 1960);
FORCEPROP 0 LASTPIN (-6725 1900) $PN CG36
J 2
(-6735 1910);
DISPLAY 0.489362 (-6735 1910);
PAINT MONO (-6735 1910);
FORCEPROP 0 LASTPIN (-6725 1850) $PN CG40
J 2
(-6735 1860);
DISPLAY 0.489362 (-6735 1860);
PAINT MONO (-6735 1860);
FORCEPROP 0 LASTPIN (-6725 1800) $PN CG41
J 2
(-6735 1810);
DISPLAY 0.489362 (-6735 1810);
PAINT MONO (-6735 1810);
FORCEPROP 0 LASTPIN (-6725 1750) $PN CH23
J 2
(-6735 1760);
DISPLAY 0.489362 (-6735 1760);
PAINT MONO (-6735 1760);
FORCEPROP 0 LASTPIN (-6725 1700) $PN CH24
J 2
(-6735 1710);
DISPLAY 0.489362 (-6735 1710);
PAINT MONO (-6735 1710);
FORCEPROP 0 LASTPIN (-6725 1650) $PN CH26
J 2
(-6735 1660);
DISPLAY 0.489362 (-6735 1660);
PAINT MONO (-6735 1660);
FORCEPROP 0 LASTPIN (-6725 1600) $PN CH27
J 2
(-6735 1610);
DISPLAY 0.489362 (-6735 1610);
PAINT MONO (-6735 1610);
FORCEPROP 0 LASTPIN (-6725 1550) $PN CH29
J 2
(-6735 1560);
DISPLAY 0.489362 (-6735 1560);
PAINT MONO (-6735 1560);
FORCEPROP 0 LASTPIN (-6725 1500) $PN CH30
J 2
(-6735 1510);
DISPLAY 0.489362 (-6735 1510);
PAINT MONO (-6735 1510);
FORCEPROP 0 LASTPIN (-6725 1450) $PN CH32
J 2
(-6735 1460);
DISPLAY 0.489362 (-6735 1460);
PAINT MONO (-6735 1460);
FORCEPROP 0 LASTPIN (-6725 1400) $PN CH33
J 2
(-6735 1410);
DISPLAY 0.489362 (-6735 1410);
PAINT MONO (-6735 1410);
FORCEPROP 0 LASTPIN (-6725 1350) $PN CH43
J 2
(-6735 1360);
DISPLAY 0.489362 (-6735 1360);
PAINT MONO (-6735 1360);
FORCEPROP 0 LASTPIN (-6725 1300) $PN CH44
J 2
(-6735 1310);
DISPLAY 0.489362 (-6735 1310);
PAINT MONO (-6735 1310);
FORCEPROP 0 LASTPIN (-6725 1250) $PN CH46
J 2
(-6735 1260);
DISPLAY 0.489362 (-6735 1260);
PAINT MONO (-6735 1260);
FORCEPROP 0 LASTPIN (-6725 1200) $PN CH47
J 2
(-6735 1210);
DISPLAY 0.489362 (-6735 1210);
PAINT MONO (-6735 1210);
FORCEPROP 0 LASTPIN (-6725 1150) $PN CH49
J 2
(-6735 1160);
DISPLAY 0.489362 (-6735 1160);
PAINT MONO (-6735 1160);
FORCEPROP 0 LASTPIN (-6725 1100) $PN CH50
J 2
(-6735 1110);
DISPLAY 0.489362 (-6735 1110);
PAINT MONO (-6735 1110);
FORCEPROP 0 LASTPIN (-6725 1050) $PN CH52
J 2
(-6735 1060);
DISPLAY 0.489362 (-6735 1060);
PAINT MONO (-6735 1060);
FORCEPROP 0 LASTPIN (-6725 1000) $PN CH53
J 2
(-6735 1010);
DISPLAY 0.489362 (-6735 1010);
PAINT MONO (-6735 1010);
FORCEPROP 0 LASTPIN (-6725 950) $PN CK35
J 2
(-6735 960);
DISPLAY 0.489362 (-6735 960);
PAINT MONO (-6735 960);
FORCEPROP 0 LASTPIN (-6725 900) $PN CK36
J 2
(-6735 910);
DISPLAY 0.489362 (-6735 910);
PAINT MONO (-6735 910);
FORCEPROP 0 LASTPIN (-6725 850) $PN CK40
J 2
(-6735 860);
DISPLAY 0.489362 (-6735 860);
PAINT MONO (-6735 860);
FORCEPROP 0 LASTPIN (-6725 800) $PN CK41
J 2
(-6735 810);
DISPLAY 0.489362 (-6735 810);
PAINT MONO (-6735 810);
FORCEPROP 0 LASTPIN (-6725 750) $PN CL29
J 2
(-6735 760);
DISPLAY 0.489362 (-6735 760);
PAINT MONO (-6735 760);
FORCEPROP 0 LASTPIN (-6725 700) $PN CL30
J 2
(-6735 710);
DISPLAY 0.489362 (-6735 710);
PAINT MONO (-6735 710);
FORCEPROP 0 LASTPIN (-5425 6400) $PN CL32
J 0
(-5415 6410);
DISPLAY 0.489362 (-5415 6410);
PAINT MONO (-5415 6410);
FORCEPROP 0 LASTPIN (-5425 6350) $PN CL33
J 0
(-5415 6360);
DISPLAY 0.489362 (-5415 6360);
PAINT MONO (-5415 6360);
FORCEPROP 0 LASTPIN (-5425 6300) $PN CL43
J 0
(-5415 6310);
DISPLAY 0.489362 (-5415 6310);
PAINT MONO (-5415 6310);
FORCEPROP 0 LASTPIN (-5425 6250) $PN CL44
J 0
(-5415 6260);
DISPLAY 0.489362 (-5415 6260);
PAINT MONO (-5415 6260);
FORCEPROP 0 LASTPIN (-5425 6200) $PN CL46
J 0
(-5415 6210);
DISPLAY 0.489362 (-5415 6210);
PAINT MONO (-5415 6210);
FORCEPROP 0 LASTPIN (-5425 6150) $PN CL47
J 0
(-5415 6160);
DISPLAY 0.489362 (-5415 6160);
PAINT MONO (-5415 6160);
FORCEPROP 0 LASTPIN (-5425 6100) $PN CN35
J 0
(-5415 6110);
DISPLAY 0.489362 (-5415 6110);
PAINT MONO (-5415 6110);
FORCEPROP 0 LASTPIN (-5425 6050) $PN CN36
J 0
(-5415 6060);
DISPLAY 0.489362 (-5415 6060);
PAINT MONO (-5415 6060);
FORCEPROP 0 LASTPIN (-5425 6000) $PN CN40
J 0
(-5415 6010);
DISPLAY 0.489362 (-5415 6010);
PAINT MONO (-5415 6010);
FORCEPROP 0 LASTPIN (-5425 5950) $PN CN41
J 0
(-5415 5960);
DISPLAY 0.489362 (-5415 5960);
PAINT MONO (-5415 5960);
FORCEPROP 0 LASTPIN (-5425 5900) $PN CP23
J 0
(-5415 5910);
DISPLAY 0.489362 (-5415 5910);
PAINT MONO (-5415 5910);
FORCEPROP 0 LASTPIN (-5425 5850) $PN CP24
J 0
(-5415 5860);
DISPLAY 0.489362 (-5415 5860);
PAINT MONO (-5415 5860);
FORCEPROP 0 LASTPIN (-5425 5800) $PN CP26
J 0
(-5415 5810);
DISPLAY 0.489362 (-5415 5810);
PAINT MONO (-5415 5810);
FORCEPROP 0 LASTPIN (-5425 5750) $PN CP27
J 0
(-5415 5760);
DISPLAY 0.489362 (-5415 5760);
PAINT MONO (-5415 5760);
FORCEPROP 0 LASTPIN (-5425 5700) $PN CP29
J 0
(-5415 5710);
DISPLAY 0.489362 (-5415 5710);
PAINT MONO (-5415 5710);
FORCEPROP 0 LASTPIN (-5425 5650) $PN CP30
J 0
(-5415 5660);
DISPLAY 0.489362 (-5415 5660);
PAINT MONO (-5415 5660);
FORCEPROP 0 LASTPIN (-5425 5600) $PN CP32
J 0
(-5415 5610);
DISPLAY 0.489362 (-5415 5610);
PAINT MONO (-5415 5610);
FORCEPROP 0 LASTPIN (-5425 5550) $PN CP33
J 0
(-5415 5560);
DISPLAY 0.489362 (-5415 5560);
PAINT MONO (-5415 5560);
FORCEPROP 0 LASTPIN (-5425 5500) $PN CP43
J 0
(-5415 5510);
DISPLAY 0.489362 (-5415 5510);
PAINT MONO (-5415 5510);
FORCEPROP 0 LASTPIN (-5425 5450) $PN CP44
J 0
(-5415 5460);
DISPLAY 0.489362 (-5415 5460);
PAINT MONO (-5415 5460);
FORCEPROP 0 LASTPIN (-5425 5400) $PN CP46
J 0
(-5415 5410);
DISPLAY 0.489362 (-5415 5410);
PAINT MONO (-5415 5410);
FORCEPROP 0 LASTPIN (-5425 5350) $PN CP47
J 0
(-5415 5360);
DISPLAY 0.489362 (-5415 5360);
PAINT MONO (-5415 5360);
FORCEPROP 0 LASTPIN (-5425 5300) $PN CP49
J 0
(-5415 5310);
DISPLAY 0.489362 (-5415 5310);
PAINT MONO (-5415 5310);
FORCEPROP 0 LASTPIN (-5425 5250) $PN CP50
J 0
(-5415 5260);
DISPLAY 0.489362 (-5415 5260);
PAINT MONO (-5415 5260);
FORCEPROP 0 LASTPIN (-5425 5200) $PN CP52
J 0
(-5415 5210);
DISPLAY 0.489362 (-5415 5210);
PAINT MONO (-5415 5210);
FORCEPROP 0 LASTPIN (-5425 5150) $PN CP53
J 0
(-5415 5160);
DISPLAY 0.489362 (-5415 5160);
PAINT MONO (-5415 5160);
FORCEPROP 0 LASTPIN (-5425 5100) $PN CU35
J 0
(-5415 5110);
DISPLAY 0.489362 (-5415 5110);
PAINT MONO (-5415 5110);
FORCEPROP 0 LASTPIN (-5425 5050) $PN CU36
J 0
(-5415 5060);
DISPLAY 0.489362 (-5415 5060);
PAINT MONO (-5415 5060);
FORCEPROP 0 LASTPIN (-5425 5000) $PN CU40
J 0
(-5415 5010);
DISPLAY 0.489362 (-5415 5010);
PAINT MONO (-5415 5010);
FORCEPROP 0 LASTPIN (-5425 4950) $PN CU41
J 0
(-5415 4960);
DISPLAY 0.489362 (-5415 4960);
PAINT MONO (-5415 4960);
FORCEPROP 0 LASTPIN (-5425 4900) $PN CV23
J 0
(-5415 4910);
DISPLAY 0.489362 (-5415 4910);
PAINT MONO (-5415 4910);
FORCEPROP 0 LASTPIN (-5425 4850) $PN CV24
J 0
(-5415 4860);
DISPLAY 0.489362 (-5415 4860);
PAINT MONO (-5415 4860);
FORCEPROP 0 LASTPIN (-5425 4800) $PN CV26
J 0
(-5415 4810);
DISPLAY 0.489362 (-5415 4810);
PAINT MONO (-5415 4810);
FORCEPROP 0 LASTPIN (-5425 4750) $PN CV27
J 0
(-5415 4760);
DISPLAY 0.489362 (-5415 4760);
PAINT MONO (-5415 4760);
FORCEPROP 0 LASTPIN (-5425 4700) $PN CV29
J 0
(-5415 4710);
DISPLAY 0.489362 (-5415 4710);
PAINT MONO (-5415 4710);
FORCEPROP 0 LASTPIN (-5425 4650) $PN CV30
J 0
(-5415 4660);
DISPLAY 0.489362 (-5415 4660);
PAINT MONO (-5415 4660);
FORCEPROP 0 LASTPIN (-5425 4600) $PN CV32
J 0
(-5415 4610);
DISPLAY 0.489362 (-5415 4610);
PAINT MONO (-5415 4610);
FORCEPROP 0 LASTPIN (-5425 4550) $PN CV33
J 0
(-5415 4560);
DISPLAY 0.489362 (-5415 4560);
PAINT MONO (-5415 4560);
FORCEPROP 0 LASTPIN (-5425 4500) $PN CV43
J 0
(-5415 4510);
DISPLAY 0.489362 (-5415 4510);
PAINT MONO (-5415 4510);
FORCEPROP 0 LASTPIN (-5425 4450) $PN CV44
J 0
(-5415 4460);
DISPLAY 0.489362 (-5415 4460);
PAINT MONO (-5415 4460);
FORCEPROP 0 LASTPIN (-5425 4400) $PN CV46
J 0
(-5415 4410);
DISPLAY 0.489362 (-5415 4410);
PAINT MONO (-5415 4410);
FORCEPROP 0 LASTPIN (-5425 4350) $PN CV47
J 0
(-5415 4360);
DISPLAY 0.489362 (-5415 4360);
PAINT MONO (-5415 4360);
FORCEPROP 0 LASTPIN (-5425 4300) $PN CV49
J 0
(-5415 4310);
DISPLAY 0.489362 (-5415 4310);
PAINT MONO (-5415 4310);
FORCEPROP 0 LASTPIN (-5425 4250) $PN CV50
J 0
(-5415 4260);
DISPLAY 0.489362 (-5415 4260);
PAINT MONO (-5415 4260);
FORCEPROP 0 LASTPIN (-5425 4200) $PN CV52
J 0
(-5415 4210);
DISPLAY 0.489362 (-5415 4210);
PAINT MONO (-5415 4210);
FORCEPROP 0 LASTPIN (-5425 4150) $PN CV53
J 0
(-5415 4160);
DISPLAY 0.489362 (-5415 4160);
PAINT MONO (-5415 4160);
FORCEPROP 0 LASTPIN (-5425 4100) $PN DA35
J 0
(-5415 4110);
DISPLAY 0.489362 (-5415 4110);
PAINT MONO (-5415 4110);
FORCEPROP 0 LASTPIN (-5425 4050) $PN DA36
J 0
(-5415 4060);
DISPLAY 0.489362 (-5415 4060);
PAINT MONO (-5415 4060);
FORCEPROP 0 LASTPIN (-5425 4000) $PN DA40
J 0
(-5415 4010);
DISPLAY 0.489362 (-5415 4010);
PAINT MONO (-5415 4010);
FORCEPROP 0 LASTPIN (-5425 3950) $PN DA41
J 0
(-5415 3960);
DISPLAY 0.489362 (-5415 3960);
PAINT MONO (-5415 3960);
FORCEPROP 0 LASTPIN (-5425 3900) $PN DB23
J 0
(-5415 3910);
DISPLAY 0.489362 (-5415 3910);
PAINT MONO (-5415 3910);
FORCEPROP 0 LASTPIN (-5425 3850) $PN DB24
J 0
(-5415 3860);
DISPLAY 0.489362 (-5415 3860);
PAINT MONO (-5415 3860);
FORCEPROP 0 LASTPIN (-5425 3800) $PN DB26
J 0
(-5415 3810);
DISPLAY 0.489362 (-5415 3810);
PAINT MONO (-5415 3810);
FORCEPROP 0 LASTPIN (-5425 3750) $PN DB27
J 0
(-5415 3760);
DISPLAY 0.489362 (-5415 3760);
PAINT MONO (-5415 3760);
FORCEPROP 0 LASTPIN (-5425 3700) $PN DB29
J 0
(-5415 3710);
DISPLAY 0.489362 (-5415 3710);
PAINT MONO (-5415 3710);
FORCEPROP 0 LASTPIN (-5425 3650) $PN DB30
J 0
(-5415 3660);
DISPLAY 0.489362 (-5415 3660);
PAINT MONO (-5415 3660);
FORCEPROP 0 LASTPIN (-5425 3600) $PN DB32
J 0
(-5415 3610);
DISPLAY 0.489362 (-5415 3610);
PAINT MONO (-5415 3610);
FORCEPROP 0 LASTPIN (-5425 3550) $PN DB33
J 0
(-5415 3560);
DISPLAY 0.489362 (-5415 3560);
PAINT MONO (-5415 3560);
FORCEPROP 0 LASTPIN (-5425 3500) $PN DB43
J 0
(-5415 3510);
DISPLAY 0.489362 (-5415 3510);
PAINT MONO (-5415 3510);
FORCEPROP 0 LASTPIN (-5425 3450) $PN DB44
J 0
(-5415 3460);
DISPLAY 0.489362 (-5415 3460);
PAINT MONO (-5415 3460);
FORCEPROP 0 LASTPIN (-5425 3400) $PN DB46
J 0
(-5415 3410);
DISPLAY 0.489362 (-5415 3410);
PAINT MONO (-5415 3410);
FORCEPROP 0 LASTPIN (-5425 3350) $PN DB47
J 0
(-5415 3360);
DISPLAY 0.489362 (-5415 3360);
PAINT MONO (-5415 3360);
FORCEPROP 0 LASTPIN (-5425 3300) $PN DB49
J 0
(-5415 3310);
DISPLAY 0.489362 (-5415 3310);
PAINT MONO (-5415 3310);
FORCEPROP 0 LASTPIN (-5425 3250) $PN DB50
J 0
(-5415 3260);
DISPLAY 0.489362 (-5415 3260);
PAINT MONO (-5415 3260);
FORCEPROP 0 LASTPIN (-5425 3200) $PN DB52
J 0
(-5415 3210);
DISPLAY 0.489362 (-5415 3210);
PAINT MONO (-5415 3210);
FORCEPROP 0 LASTPIN (-5425 3150) $PN DB53
J 0
(-5415 3160);
DISPLAY 0.489362 (-5415 3160);
PAINT MONO (-5415 3160);
FORCEPROP 0 LASTPIN (-5425 3100) $PN DC35
J 0
(-5415 3110);
DISPLAY 0.489362 (-5415 3110);
PAINT MONO (-5415 3110);
FORCEPROP 0 LASTPIN (-5425 3050) $PN DC36
J 0
(-5415 3060);
DISPLAY 0.489362 (-5415 3060);
PAINT MONO (-5415 3060);
FORCEPROP 0 LASTPIN (-5425 3000) $PN DC40
J 0
(-5415 3010);
DISPLAY 0.489362 (-5415 3010);
PAINT MONO (-5415 3010);
FORCEPROP 0 LASTPIN (-5425 2950) $PN DC41
J 0
(-5415 2960);
DISPLAY 0.489362 (-5415 2960);
PAINT MONO (-5415 2960);
FORCEPROP 0 LASTPIN (-5425 2900) $PN DD22
J 0
(-5415 2910);
DISPLAY 0.489362 (-5415 2910);
PAINT MONO (-5415 2910);
FORCEPROP 0 LASTPIN (-5425 2850) $PN DD25
J 0
(-5415 2860);
DISPLAY 0.489362 (-5415 2860);
PAINT MONO (-5415 2860);
FORCEPROP 0 LASTPIN (-5425 2800) $PN DD28
J 0
(-5415 2810);
DISPLAY 0.489362 (-5415 2810);
PAINT MONO (-5415 2810);
FORCEPROP 0 LASTPIN (-5425 2750) $PN DD31
J 0
(-5415 2760);
DISPLAY 0.489362 (-5415 2760);
PAINT MONO (-5415 2760);
FORCEPROP 0 LASTPIN (-5425 2700) $PN DD34
J 0
(-5415 2710);
DISPLAY 0.489362 (-5415 2710);
PAINT MONO (-5415 2710);
FORCEPROP 0 LASTPIN (-5425 2650) $PN DD42
J 0
(-5415 2660);
DISPLAY 0.489362 (-5415 2660);
PAINT MONO (-5415 2660);
FORCEPROP 0 LASTPIN (-5425 2600) $PN DD45
J 0
(-5415 2610);
DISPLAY 0.489362 (-5415 2610);
PAINT MONO (-5415 2610);
FORCEPROP 0 LASTPIN (-5425 2550) $PN DD48
J 0
(-5415 2560);
DISPLAY 0.489362 (-5415 2560);
PAINT MONO (-5415 2560);
FORCEPROP 0 LASTPIN (-5425 2500) $PN DD51
J 0
(-5415 2510);
DISPLAY 0.489362 (-5415 2510);
PAINT MONO (-5415 2510);
FORCEPROP 0 LASTPIN (-5425 2450) $PN DD54
J 0
(-5415 2460);
DISPLAY 0.489362 (-5415 2460);
PAINT MONO (-5415 2460);
FORCEPROP 0 LASTPIN (-5425 2400) $PN DE22
J 0
(-5415 2410);
DISPLAY 0.489362 (-5415 2410);
PAINT MONO (-5415 2410);
FORCEPROP 0 LASTPIN (-5425 2350) $PN DE25
J 0
(-5415 2360);
DISPLAY 0.489362 (-5415 2360);
PAINT MONO (-5415 2360);
FORCEPROP 0 LASTPIN (-5425 2300) $PN DE28
J 0
(-5415 2310);
DISPLAY 0.489362 (-5415 2310);
PAINT MONO (-5415 2310);
FORCEPROP 0 LASTPIN (-5425 2250) $PN DE31
J 0
(-5415 2260);
DISPLAY 0.489362 (-5415 2260);
PAINT MONO (-5415 2260);
FORCEPROP 0 LASTPIN (-5425 2200) $PN DE34
J 0
(-5415 2210);
DISPLAY 0.489362 (-5415 2210);
PAINT MONO (-5415 2210);
FORCEPROP 0 LASTPIN (-5425 2150) $PN DE35
J 0
(-5415 2160);
DISPLAY 0.489362 (-5415 2160);
PAINT MONO (-5415 2160);
FORCEPROP 0 LASTPIN (-5425 2100) $PN DE41
J 0
(-5415 2110);
DISPLAY 0.489362 (-5415 2110);
PAINT MONO (-5415 2110);
FORCEPROP 0 LASTPIN (-5425 2050) $PN DE42
J 0
(-5415 2060);
DISPLAY 0.489362 (-5415 2060);
PAINT MONO (-5415 2060);
FORCEPROP 0 LASTPIN (-5425 2000) $PN DE45
J 0
(-5415 2010);
DISPLAY 0.489362 (-5415 2010);
PAINT MONO (-5415 2010);
FORCEPROP 0 LASTPIN (-5425 1950) $PN DE48
J 0
(-5415 1960);
DISPLAY 0.489362 (-5415 1960);
PAINT MONO (-5415 1960);
FORCEPROP 0 LASTPIN (-5425 1900) $PN DE51
J 0
(-5415 1910);
DISPLAY 0.489362 (-5415 1910);
PAINT MONO (-5415 1910);
FORCEPROP 0 LASTPIN (-5425 1850) $PN DE54
J 0
(-5415 1860);
DISPLAY 0.489362 (-5415 1860);
PAINT MONO (-5415 1860);
FORCEPROP 0 LASTPIN (-5425 1800) $PN DG19
J 0
(-5415 1810);
DISPLAY 0.489362 (-5415 1810);
PAINT MONO (-5415 1810);
FORCEPROP 0 LASTPIN (-5425 1750) $PN DG57
J 0
(-5415 1760);
DISPLAY 0.489362 (-5415 1760);
PAINT MONO (-5415 1760);
FORCEPROP 0 LASTPIN (-5425 1700) $PN DH19
J 0
(-5415 1710);
DISPLAY 0.489362 (-5415 1710);
PAINT MONO (-5415 1710);
FORCEPROP 0 LASTPIN (-5425 1650) $PN DH20
J 0
(-5415 1660);
DISPLAY 0.489362 (-5415 1660);
PAINT MONO (-5415 1660);
FORCEPROP 0 LASTPIN (-5425 1600) $PN DH22
J 0
(-5415 1610);
DISPLAY 0.489362 (-5415 1610);
PAINT MONO (-5415 1610);
FORCEPROP 0 LASTPIN (-5425 1550) $PN DH23
J 0
(-5415 1560);
DISPLAY 0.489362 (-5415 1560);
PAINT MONO (-5415 1560);
FORCEPROP 0 LASTPIN (-5425 1500) $PN DH25
J 0
(-5415 1510);
DISPLAY 0.489362 (-5415 1510);
PAINT MONO (-5415 1510);
FORCEPROP 0 LASTPIN (-5425 1450) $PN DH26
J 0
(-5415 1460);
DISPLAY 0.489362 (-5415 1460);
PAINT MONO (-5415 1460);
FORCEPROP 0 LASTPIN (-5425 1400) $PN DH28
J 0
(-5415 1410);
DISPLAY 0.489362 (-5415 1410);
PAINT MONO (-5415 1410);
FORCEPROP 0 LASTPIN (-5425 1350) $PN DH29
J 0
(-5415 1360);
DISPLAY 0.489362 (-5415 1360);
PAINT MONO (-5415 1360);
FORCEPROP 0 LASTPIN (-5425 1300) $PN DH31
J 0
(-5415 1310);
DISPLAY 0.489362 (-5415 1310);
PAINT MONO (-5415 1310);
FORCEPROP 0 LASTPIN (-5425 1250) $PN DH32
J 0
(-5415 1260);
DISPLAY 0.489362 (-5415 1260);
PAINT MONO (-5415 1260);
FORCEPROP 0 LASTPIN (-5425 1200) $PN DH34
J 0
(-5415 1210);
DISPLAY 0.489362 (-5415 1210);
PAINT MONO (-5415 1210);
FORCEPROP 0 LASTPIN (-5425 1150) $PN DH35
J 0
(-5415 1160);
DISPLAY 0.489362 (-5415 1160);
PAINT MONO (-5415 1160);
FORCEPROP 0 LASTPIN (-5425 1100) $PN DH41
J 0
(-5415 1110);
DISPLAY 0.489362 (-5415 1110);
PAINT MONO (-5415 1110);
FORCEPROP 0 LASTPIN (-5425 1050) $PN DH42
J 0
(-5415 1060);
DISPLAY 0.489362 (-5415 1060);
PAINT MONO (-5415 1060);
FORCEPROP 0 LASTPIN (-5425 1000) $PN DH44
J 0
(-5415 1010);
DISPLAY 0.489362 (-5415 1010);
PAINT MONO (-5415 1010);
FORCEPROP 0 LASTPIN (-5425 950) $PN DH45
J 0
(-5415 960);
DISPLAY 0.489362 (-5415 960);
PAINT MONO (-5415 960);
FORCEPROP 0 LASTPIN (-5425 900) $PN DH47
J 0
(-5415 910);
DISPLAY 0.489362 (-5415 910);
PAINT MONO (-5415 910);
FORCEPROP 0 LASTPIN (-5425 850) $PN DH48
J 0
(-5415 860);
DISPLAY 0.489362 (-5415 860);
PAINT MONO (-5415 860);
FORCEPROP 0 LASTPIN (-5425 800) $PN DH50
J 0
(-5415 810);
DISPLAY 0.489362 (-5415 810);
PAINT MONO (-5415 810);
FORCEPROP 0 LASTPIN (-5425 750) $PN DH51
J 0
(-5415 760);
DISPLAY 0.489362 (-5415 760);
PAINT MONO (-5415 760);
FORCEPROP 0 LASTPIN (-5425 700) $PN DH53
J 0
(-5415 710);
DISPLAY 0.489362 (-5415 710);
PAINT MONO (-5415 710);
FORCEPROP 0 LASTPIN (-5425 650) $PN DH54
J 0
(-5415 660);
DISPLAY 0.489362 (-5415 660);
PAINT MONO (-5415 660);
FORCEPROP 0 LASTPIN (-5425 600) $PN DH56
J 0
(-5415 610);
DISPLAY 0.489362 (-5415 610);
PAINT MONO (-5415 610);
FORCEPROP 0 LASTPIN (-5425 550) $PN DH57
J 0
(-5415 560);
DISPLAY 0.489362 (-5415 560);
PAINT MONO (-5415 560);
FORCEPROP 2 LAST PART_TYPE SMLF
J 0
(-6800 6675);
DISPLAY 1.021277 (-6800 6675);
FORCEPROP 1 LAST MATERIAL IO
J 0
(-6570 6582);
DISPLAY 0.489362 (-6570 6582);
PAINT SKYBLUE (-6570 6582);
FORCEPROP 2 LAST VALUE SOCKET6096_13568-001
J 0
(-6800 6625);
DISPLAY 0.489362 (-6800 6625);
PAINT SKYBLUE (-6800 6625);
FORCEPROP 1 LAST PART_NUMBER DGA^6000030
J 0
(-6570 6709);
DISPLAY 0.489362 (-6570 6709);
PAINT SKYBLUE (-6570 6709);
FORCEPROP 1 LAST CDS_LMAN_SYM_OUTLINE -500,3200,500,-3200
J 0
(-6075 3350);
DISPLAY 0.468085 (-6075 3350);
PAINT GREEN (-6075 3350);
DISPLAY INVISIBLE (-6075 3350);
FORCEPROP 2 LAST CDS_LIB pure_quanta
J 0
(-6075 3350);
DISPLAY INVISIBLE (-6075 3350);
FORCEPROP 1 LAST NEEDS_NO_SIZE TRUE
J 0
(-6075 3350);
DISPLAY 0.723404 (-6075 3350);
PAINT GREEN (-6075 3350);
DISPLAY INVISIBLE (-6075 3350);
FORCEPROP 1 LAST PATH I45
J 0
(-6075 3350);
DISPLAY 0.723404 (-6075 3350);
PAINT GREEN (-6075 3350);
DISPLAY INVISIBLE (-6075 3350);
FORCEADD VCC_CORE..1
(-5275 6475);
FORCEPROP 3 LASTPIN (-5275 6425) SIG_NAME PVDDCR_CPU1_P0\g
J 0
(-5265 6435);
DISPLAY 0.659574 (-5265 6435);
PAINT MONO (-5265 6435);
DISPLAY INVISIBLE (-5265 6435);
FORCEPROP 1 LAST HDL_POWER PVDDCR_CPU1_P0
J 1
(-5275 6525);
DISPLAY 0.489362 (-5275 6525);
PAINT GREEN (-5275 6525);
FORCEPROP 2 LAST CDS_LIB pure_quanta_power
J 0
(-5275 6475);
DISPLAY INVISIBLE (-5275 6475);
FORCEPROP 1 LAST PATH I46
J 0
(-5225 6500);
DISPLAY 0.872340 (-5225 6500);
PAINT AQUA (-5225 6500);
DISPLAY INVISIBLE (-5225 6500);
FORCEADD VCC_CORE..1
(-6900 6225);
FORCEPROP 3 LASTPIN (-6900 6175) SIG_NAME PVDDCR_CPU1_P0\g
J 0
(-6890 6185);
DISPLAY 0.659574 (-6890 6185);
PAINT MONO (-6890 6185);
DISPLAY INVISIBLE (-6890 6185);
FORCEPROP 1 LAST HDL_POWER PVDDCR_CPU1_P0
J 1
(-6900 6275);
DISPLAY 0.489362 (-6900 6275);
PAINT GREEN (-6900 6275);
FORCEPROP 2 LAST CDS_LIB pure_quanta_power
J 0
(-6900 6225);
DISPLAY INVISIBLE (-6900 6225);
FORCEPROP 1 LAST PATH I47
J 0
(-6850 6250);
DISPLAY 0.872340 (-6850 6250);
PAINT AQUA (-6850 6250);
DISPLAY INVISIBLE (-6850 6250);
FORCEADD GENOA_SP5..26
(-4250 4575);
FORCEPROP 1 LAST LOCATION U25
J 0
(-4700 6375);
DISPLAY 0.489362 (-4700 6375);
PAINT SKYBLUE (-4700 6375);
FORCEPROP 0 LAST $SEC 26
J 0
(-4675 6575);
DISPLAY 0.680851 (-4675 6575);
PAINT MONO (-4675 6575);
DISPLAY INVISIBLE (-4675 6575);
FORCEPROP 0 LAST CDS_SEC 26
J 0
(-4700 6475);
DISPLAY 1.021277 (-4700 6475);
DISPLAY INVISIBLE (-4700 6475);
FORCEPROP 0 LASTPIN (-4850 4925) $PN AA22
J 2
(-4860 4935);
DISPLAY 0.489362 (-4860 4935);
PAINT MONO (-4860 4935);
FORCEPROP 0 LASTPIN (-4850 4875) $PN AC4
J 2
(-4860 4885);
DISPLAY 0.489362 (-4860 4885);
PAINT MONO (-4860 4885);
FORCEPROP 0 LASTPIN (-4850 4825) $PN AC11
J 2
(-4860 4835);
DISPLAY 0.489362 (-4860 4835);
PAINT MONO (-4860 4835);
FORCEPROP 0 LASTPIN (-4850 4775) $PN AC18
J 2
(-4860 4785);
DISPLAY 0.489362 (-4860 4785);
PAINT MONO (-4860 4785);
FORCEPROP 0 LASTPIN (-4850 4725) $PN AD22
J 2
(-4860 4735);
DISPLAY 0.489362 (-4860 4735);
PAINT MONO (-4860 4735);
FORCEPROP 0 LASTPIN (-4850 4675) $PN AF5
J 2
(-4860 4685);
DISPLAY 0.489362 (-4860 4685);
PAINT MONO (-4860 4685);
FORCEPROP 0 LASTPIN (-4850 4625) $PN AF12
J 2
(-4860 4635);
DISPLAY 0.489362 (-4860 4635);
PAINT MONO (-4860 4635);
FORCEPROP 0 LASTPIN (-4850 4575) $PN AF19
J 2
(-4860 4585);
DISPLAY 0.489362 (-4860 4585);
PAINT MONO (-4860 4585);
FORCEPROP 0 LASTPIN (-4850 4525) $PN AH22
J 2
(-4860 4535);
DISPLAY 0.489362 (-4860 4535);
PAINT MONO (-4860 4535);
FORCEPROP 0 LASTPIN (-4850 4475) $PN AJ4
J 2
(-4860 4485);
DISPLAY 0.489362 (-4860 4485);
PAINT MONO (-4860 4485);
FORCEPROP 0 LASTPIN (-4850 4425) $PN AJ11
J 2
(-4860 4435);
DISPLAY 0.489362 (-4860 4435);
PAINT MONO (-4860 4435);
FORCEPROP 0 LASTPIN (-4850 4375) $PN AJ18
J 2
(-4860 4385);
DISPLAY 0.489362 (-4860 4385);
PAINT MONO (-4860 4385);
FORCEPROP 0 LASTPIN (-4850 4325) $PN AM5
J 2
(-4860 4335);
DISPLAY 0.489362 (-4860 4335);
PAINT MONO (-4860 4335);
FORCEPROP 0 LASTPIN (-4850 4275) $PN AM12
J 2
(-4860 4285);
DISPLAY 0.489362 (-4860 4285);
PAINT MONO (-4860 4285);
FORCEPROP 0 LASTPIN (-4850 4225) $PN AM19
J 2
(-4860 4235);
DISPLAY 0.489362 (-4860 4235);
PAINT MONO (-4860 4235);
FORCEPROP 0 LASTPIN (-4850 4175) $PN AM22
J 2
(-4860 4185);
DISPLAY 0.489362 (-4860 4185);
PAINT MONO (-4860 4185);
FORCEPROP 0 LASTPIN (-4850 4125) $PN AR4
J 2
(-4860 4135);
DISPLAY 0.489362 (-4860 4135);
PAINT MONO (-4860 4135);
FORCEPROP 0 LASTPIN (-4850 4075) $PN AR11
J 2
(-4860 4085);
DISPLAY 0.489362 (-4860 4085);
PAINT MONO (-4860 4085);
FORCEPROP 0 LASTPIN (-4850 4025) $PN AR18
J 2
(-4860 4035);
DISPLAY 0.489362 (-4860 4035);
PAINT MONO (-4860 4035);
FORCEPROP 0 LASTPIN (-4850 3975) $PN AT22
J 2
(-4860 3985);
DISPLAY 0.489362 (-4860 3985);
PAINT MONO (-4860 3985);
FORCEPROP 0 LASTPIN (-4850 3925) $PN AU23
J 2
(-4860 3935);
DISPLAY 0.489362 (-4860 3935);
PAINT MONO (-4860 3935);
FORCEPROP 0 LASTPIN (-4850 3875) $PN AU27
J 2
(-4860 3885);
DISPLAY 0.489362 (-4860 3885);
PAINT MONO (-4860 3885);
FORCEPROP 0 LASTPIN (-4850 3825) $PN AU31
J 2
(-4860 3835);
DISPLAY 0.489362 (-4860 3835);
PAINT MONO (-4860 3835);
FORCEPROP 0 LASTPIN (-4850 3775) $PN AU35
J 2
(-4860 3785);
DISPLAY 0.489362 (-4860 3785);
PAINT MONO (-4860 3785);
FORCEPROP 0 LASTPIN (-4850 3725) $PN AU40
J 2
(-4860 3735);
DISPLAY 0.489362 (-4860 3735);
PAINT MONO (-4860 3735);
FORCEPROP 0 LASTPIN (-4850 3675) $PN AV5
J 2
(-4860 3685);
DISPLAY 0.489362 (-4860 3685);
PAINT MONO (-4860 3685);
FORCEPROP 0 LASTPIN (-4850 3625) $PN AV12
J 2
(-4860 3635);
DISPLAY 0.489362 (-4860 3635);
PAINT MONO (-4860 3635);
FORCEPROP 0 LASTPIN (-4850 3575) $PN AV19
J 2
(-4860 3585);
DISPLAY 0.489362 (-4860 3585);
PAINT MONO (-4860 3585);
FORCEPROP 0 LASTPIN (-4850 3525) $PN AV22
J 2
(-4860 3535);
DISPLAY 0.489362 (-4860 3535);
PAINT MONO (-4860 3535);
FORCEPROP 0 LASTPIN (-4850 3475) $PN AV24
J 2
(-4860 3485);
DISPLAY 0.489362 (-4860 3485);
PAINT MONO (-4860 3485);
FORCEPROP 0 LASTPIN (-4850 3425) $PN AV26
J 2
(-4860 3435);
DISPLAY 0.489362 (-4860 3435);
PAINT MONO (-4860 3435);
FORCEPROP 0 LASTPIN (-4850 3375) $PN AV28
J 2
(-4860 3385);
DISPLAY 0.489362 (-4860 3385);
PAINT MONO (-4860 3385);
FORCEPROP 0 LASTPIN (-4850 3325) $PN AV30
J 2
(-4860 3335);
DISPLAY 0.489362 (-4860 3335);
PAINT MONO (-4860 3335);
FORCEPROP 0 LASTPIN (-4850 3275) $PN AV32
J 2
(-4860 3285);
DISPLAY 0.489362 (-4860 3285);
PAINT MONO (-4860 3285);
FORCEPROP 0 LASTPIN (-4850 3225) $PN AV34
J 2
(-4860 3235);
DISPLAY 0.489362 (-4860 3235);
PAINT MONO (-4860 3235);
FORCEPROP 0 LASTPIN (-4850 3175) $PN AV36
J 2
(-4860 3185);
DISPLAY 0.489362 (-4860 3185);
PAINT MONO (-4860 3185);
FORCEPROP 0 LASTPIN (-4850 3125) $PN AV39
J 2
(-4860 3135);
DISPLAY 0.489362 (-4860 3135);
PAINT MONO (-4860 3135);
FORCEPROP 0 LASTPIN (-4850 3075) $PN AV41
J 2
(-4860 3085);
DISPLAY 0.489362 (-4860 3085);
PAINT MONO (-4860 3085);
FORCEPROP 0 LASTPIN (-3650 6025) $PN AV43
J 0
(-3640 6035);
DISPLAY 0.489362 (-3640 6035);
PAINT MONO (-3640 6035);
FORCEPROP 0 LASTPIN (-3650 5975) $PN AV45
J 0
(-3640 5985);
DISPLAY 0.489362 (-3640 5985);
PAINT MONO (-3640 5985);
FORCEPROP 0 LASTPIN (-3650 5925) $PN AV47
J 0
(-3640 5935);
DISPLAY 0.489362 (-3640 5935);
PAINT MONO (-3640 5935);
FORCEPROP 0 LASTPIN (-3650 5875) $PN AW23
J 0
(-3640 5885);
DISPLAY 0.489362 (-3640 5885);
PAINT MONO (-3640 5885);
FORCEPROP 0 LASTPIN (-3650 5825) $PN AW25
J 0
(-3640 5835);
DISPLAY 0.489362 (-3640 5835);
PAINT MONO (-3640 5835);
FORCEPROP 0 LASTPIN (-3650 5775) $PN AW27
J 0
(-3640 5785);
DISPLAY 0.489362 (-3640 5785);
PAINT MONO (-3640 5785);
FORCEPROP 0 LASTPIN (-3650 5725) $PN AW48
J 0
(-3640 5735);
DISPLAY 0.489362 (-3640 5735);
PAINT MONO (-3640 5735);
FORCEPROP 0 LASTPIN (-3650 5675) $PN AY22
J 0
(-3640 5685);
DISPLAY 0.489362 (-3640 5685);
PAINT MONO (-3640 5685);
FORCEPROP 0 LASTPIN (-3650 5625) $PN AY24
J 0
(-3640 5635);
DISPLAY 0.489362 (-3640 5635);
PAINT MONO (-3640 5635);
FORCEPROP 0 LASTPIN (-3650 5575) $PN AY26
J 0
(-3640 5585);
DISPLAY 0.489362 (-3640 5585);
PAINT MONO (-3640 5585);
FORCEPROP 0 LASTPIN (-3650 5525) $PN AY28
J 0
(-3640 5535);
DISPLAY 0.489362 (-3640 5535);
PAINT MONO (-3640 5535);
FORCEPROP 0 LASTPIN (-3650 5475) $PN AY49
J 0
(-3640 5485);
DISPLAY 0.489362 (-3640 5485);
PAINT MONO (-3640 5485);
FORCEPROP 0 LASTPIN (-4850 6025) $PN B5
J 2
(-4860 6035);
DISPLAY 0.489362 (-4860 6035);
PAINT MONO (-4860 6035);
FORCEPROP 0 LASTPIN (-3650 5425) $PN BA4
J 0
(-3640 5435);
DISPLAY 0.489362 (-3640 5435);
PAINT MONO (-3640 5435);
FORCEPROP 0 LASTPIN (-3650 5375) $PN BA11
J 0
(-3640 5385);
DISPLAY 0.489362 (-3640 5385);
PAINT MONO (-3640 5385);
FORCEPROP 0 LASTPIN (-3650 5325) $PN BA18
J 0
(-3640 5335);
DISPLAY 0.489362 (-3640 5335);
PAINT MONO (-3640 5335);
FORCEPROP 0 LASTPIN (-3650 5275) $PN BA23
J 0
(-3640 5285);
DISPLAY 0.489362 (-3640 5285);
PAINT MONO (-3640 5285);
FORCEPROP 0 LASTPIN (-3650 5225) $PN BA25
J 0
(-3640 5235);
DISPLAY 0.489362 (-3640 5235);
PAINT MONO (-3640 5235);
FORCEPROP 0 LASTPIN (-3650 5175) $PN BA27
J 0
(-3640 5185);
DISPLAY 0.489362 (-3640 5185);
PAINT MONO (-3640 5185);
FORCEPROP 0 LASTPIN (-3650 5125) $PN BA48
J 0
(-3640 5135);
DISPLAY 0.489362 (-3640 5135);
PAINT MONO (-3640 5135);
FORCEPROP 0 LASTPIN (-3650 5075) $PN BB22
J 0
(-3640 5085);
DISPLAY 0.489362 (-3640 5085);
PAINT MONO (-3640 5085);
FORCEPROP 0 LASTPIN (-3650 5025) $PN BB24
J 0
(-3640 5035);
DISPLAY 0.489362 (-3640 5035);
PAINT MONO (-3640 5035);
FORCEPROP 0 LASTPIN (-3650 4975) $PN BB26
J 0
(-3640 4985);
DISPLAY 0.489362 (-3640 4985);
PAINT MONO (-3640 4985);
FORCEPROP 0 LASTPIN (-3650 4925) $PN BB28
J 0
(-3640 4935);
DISPLAY 0.489362 (-3640 4935);
PAINT MONO (-3640 4935);
FORCEPROP 0 LASTPIN (-3650 4875) $PN BB49
J 0
(-3640 4885);
DISPLAY 0.489362 (-3640 4885);
PAINT MONO (-3640 4885);
FORCEPROP 0 LASTPIN (-3650 4825) $PN BC23
J 0
(-3640 4835);
DISPLAY 0.489362 (-3640 4835);
PAINT MONO (-3640 4835);
FORCEPROP 0 LASTPIN (-3650 4775) $PN BC25
J 0
(-3640 4785);
DISPLAY 0.489362 (-3640 4785);
PAINT MONO (-3640 4785);
FORCEPROP 0 LASTPIN (-3650 4725) $PN BC27
J 0
(-3640 4735);
DISPLAY 0.489362 (-3640 4735);
PAINT MONO (-3640 4735);
FORCEPROP 0 LASTPIN (-3650 4675) $PN BC48
J 0
(-3640 4685);
DISPLAY 0.489362 (-3640 4685);
PAINT MONO (-3640 4685);
FORCEPROP 0 LASTPIN (-3650 4625) $PN BD5
J 0
(-3640 4635);
DISPLAY 0.489362 (-3640 4635);
PAINT MONO (-3640 4635);
FORCEPROP 0 LASTPIN (-3650 4575) $PN BD12
J 0
(-3640 4585);
DISPLAY 0.489362 (-3640 4585);
PAINT MONO (-3640 4585);
FORCEPROP 0 LASTPIN (-3650 4525) $PN BD19
J 0
(-3640 4535);
DISPLAY 0.489362 (-3640 4535);
PAINT MONO (-3640 4535);
FORCEPROP 0 LASTPIN (-3650 4475) $PN BD22
J 0
(-3640 4485);
DISPLAY 0.489362 (-3640 4485);
PAINT MONO (-3640 4485);
FORCEPROP 0 LASTPIN (-3650 4425) $PN BD24
J 0
(-3640 4435);
DISPLAY 0.489362 (-3640 4435);
PAINT MONO (-3640 4435);
FORCEPROP 0 LASTPIN (-3650 4375) $PN BD26
J 0
(-3640 4385);
DISPLAY 0.489362 (-3640 4385);
PAINT MONO (-3640 4385);
FORCEPROP 0 LASTPIN (-3650 4325) $PN BD28
J 0
(-3640 4335);
DISPLAY 0.489362 (-3640 4335);
PAINT MONO (-3640 4335);
FORCEPROP 0 LASTPIN (-3650 4275) $PN BD48
J 0
(-3640 4285);
DISPLAY 0.489362 (-3640 4285);
PAINT MONO (-3640 4285);
FORCEPROP 0 LASTPIN (-3650 4225) $PN BF23
J 0
(-3640 4235);
DISPLAY 0.489362 (-3640 4235);
PAINT MONO (-3640 4235);
FORCEPROP 0 LASTPIN (-3650 4175) $PN BF25
J 0
(-3640 4185);
DISPLAY 0.489362 (-3640 4185);
PAINT MONO (-3640 4185);
FORCEPROP 0 LASTPIN (-3650 4125) $PN BF27
J 0
(-3640 4135);
DISPLAY 0.489362 (-3640 4135);
PAINT MONO (-3640 4135);
FORCEPROP 0 LASTPIN (-3650 4075) $PN BF48
J 0
(-3640 4085);
DISPLAY 0.489362 (-3640 4085);
PAINT MONO (-3640 4085);
FORCEPROP 0 LASTPIN (-3650 4025) $PN BG22
J 0
(-3640 4035);
DISPLAY 0.489362 (-3640 4035);
PAINT MONO (-3640 4035);
FORCEPROP 0 LASTPIN (-3650 3975) $PN BG24
J 0
(-3640 3985);
DISPLAY 0.489362 (-3640 3985);
PAINT MONO (-3640 3985);
FORCEPROP 0 LASTPIN (-3650 3925) $PN BG26
J 0
(-3640 3935);
DISPLAY 0.489362 (-3640 3935);
PAINT MONO (-3640 3935);
FORCEPROP 0 LASTPIN (-3650 3875) $PN BG28
J 0
(-3640 3885);
DISPLAY 0.489362 (-3640 3885);
PAINT MONO (-3640 3885);
FORCEPROP 0 LASTPIN (-3650 3825) $PN BG48
J 0
(-3640 3835);
DISPLAY 0.489362 (-3640 3835);
PAINT MONO (-3640 3835);
FORCEPROP 0 LASTPIN (-3650 3775) $PN BH23
J 0
(-3640 3785);
DISPLAY 0.489362 (-3640 3785);
PAINT MONO (-3640 3785);
FORCEPROP 0 LASTPIN (-3650 3725) $PN BH25
J 0
(-3640 3735);
DISPLAY 0.489362 (-3640 3735);
PAINT MONO (-3640 3735);
FORCEPROP 0 LASTPIN (-3650 3675) $PN BH48
J 0
(-3640 3685);
DISPLAY 0.489362 (-3640 3685);
PAINT MONO (-3640 3685);
FORCEPROP 0 LASTPIN (-3650 3625) $PN BJ4
J 0
(-3640 3635);
DISPLAY 0.489362 (-3640 3635);
PAINT MONO (-3640 3635);
FORCEPROP 0 LASTPIN (-3650 3575) $PN BJ11
J 0
(-3640 3585);
DISPLAY 0.489362 (-3640 3585);
PAINT MONO (-3640 3585);
FORCEPROP 0 LASTPIN (-3650 3525) $PN BJ48
J 0
(-3640 3535);
DISPLAY 0.489362 (-3640 3535);
PAINT MONO (-3640 3535);
FORCEPROP 0 LASTPIN (-3650 3475) $PN BM5
J 0
(-3640 3485);
DISPLAY 0.489362 (-3640 3485);
PAINT MONO (-3640 3485);
FORCEPROP 0 LASTPIN (-4850 5975) $PN C4
J 2
(-4860 5985);
DISPLAY 0.489362 (-4860 5985);
PAINT MONO (-4860 5985);
FORCEPROP 0 LASTPIN (-4850 5925) $PN E4
J 2
(-4860 5935);
DISPLAY 0.489362 (-4860 5935);
PAINT MONO (-4860 5935);
FORCEPROP 0 LASTPIN (-4850 5875) $PN E11
J 2
(-4860 5885);
DISPLAY 0.489362 (-4860 5885);
PAINT MONO (-4860 5885);
FORCEPROP 0 LASTPIN (-4850 5825) $PN H5
J 2
(-4860 5835);
DISPLAY 0.489362 (-4860 5835);
PAINT MONO (-4860 5835);
FORCEPROP 0 LASTPIN (-4850 5775) $PN H12
J 2
(-4860 5785);
DISPLAY 0.489362 (-4860 5785);
PAINT MONO (-4860 5785);
FORCEPROP 0 LASTPIN (-4850 5725) $PN H19
J 2
(-4860 5735);
DISPLAY 0.489362 (-4860 5735);
PAINT MONO (-4860 5735);
FORCEPROP 0 LASTPIN (-4850 5675) $PN K22
J 2
(-4860 5685);
DISPLAY 0.489362 (-4860 5685);
PAINT MONO (-4860 5685);
FORCEPROP 0 LASTPIN (-4850 5625) $PN L4
J 2
(-4860 5635);
DISPLAY 0.489362 (-4860 5635);
PAINT MONO (-4860 5635);
FORCEPROP 0 LASTPIN (-4850 5575) $PN L11
J 2
(-4860 5585);
DISPLAY 0.489362 (-4860 5585);
PAINT MONO (-4860 5585);
FORCEPROP 0 LASTPIN (-4850 5525) $PN L18
J 2
(-4860 5535);
DISPLAY 0.489362 (-4860 5535);
PAINT MONO (-4860 5535);
FORCEPROP 0 LASTPIN (-4850 5475) $PN P5
J 2
(-4860 5485);
DISPLAY 0.489362 (-4860 5485);
PAINT MONO (-4860 5485);
FORCEPROP 0 LASTPIN (-4850 5425) $PN P12
J 2
(-4860 5435);
DISPLAY 0.489362 (-4860 5435);
PAINT MONO (-4860 5435);
FORCEPROP 0 LASTPIN (-4850 5375) $PN P19
J 2
(-4860 5385);
DISPLAY 0.489362 (-4860 5385);
PAINT MONO (-4860 5385);
FORCEPROP 0 LASTPIN (-4850 5325) $PN P22
J 2
(-4860 5335);
DISPLAY 0.489362 (-4860 5335);
PAINT MONO (-4860 5335);
FORCEPROP 0 LASTPIN (-4850 5275) $PN U4
J 2
(-4860 5285);
DISPLAY 0.489362 (-4860 5285);
PAINT MONO (-4860 5285);
FORCEPROP 0 LASTPIN (-4850 5225) $PN U11
J 2
(-4860 5235);
DISPLAY 0.489362 (-4860 5235);
PAINT MONO (-4860 5235);
FORCEPROP 0 LASTPIN (-4850 5175) $PN U18
J 2
(-4860 5185);
DISPLAY 0.489362 (-4860 5185);
PAINT MONO (-4860 5185);
FORCEPROP 0 LASTPIN (-4850 5125) $PN V22
J 2
(-4860 5135);
DISPLAY 0.489362 (-4860 5135);
PAINT MONO (-4860 5135);
FORCEPROP 0 LASTPIN (-4850 5075) $PN Y5
J 2
(-4860 5085);
DISPLAY 0.489362 (-4860 5085);
PAINT MONO (-4860 5085);
FORCEPROP 0 LASTPIN (-4850 5025) $PN Y12
J 2
(-4860 5035);
DISPLAY 0.489362 (-4860 5035);
PAINT MONO (-4860 5035);
FORCEPROP 0 LASTPIN (-4850 4975) $PN Y19
J 2
(-4860 4985);
DISPLAY 0.489362 (-4860 4985);
PAINT MONO (-4860 4985);
FORCEPROP 2 LAST PART_TYPE SMLF
J 0
(-4700 6525);
DISPLAY 1.021277 (-4700 6525);
FORCEPROP 1 LAST MATERIAL IO
J 0
(-4695 6257);
DISPLAY 0.489362 (-4695 6257);
PAINT SKYBLUE (-4695 6257);
FORCEPROP 2 LAST VALUE SOCKET6096_13568-001
J 0
(-4700 6325);
DISPLAY 0.489362 (-4700 6325);
PAINT SKYBLUE (-4700 6325);
FORCEPROP 1 LAST PART_NUMBER DGA^6000030
J 0
(-4700 6450);
DISPLAY 0.489362 (-4700 6450);
PAINT SKYBLUE (-4700 6450);
FORCEPROP 1 LAST CDS_LMAN_SYM_OUTLINE -450,1650,450,-1650
J 0
(-4250 4575);
DISPLAY 0.468085 (-4250 4575);
PAINT GREEN (-4250 4575);
DISPLAY INVISIBLE (-4250 4575);
FORCEPROP 1 LAST NEEDS_NO_SIZE TRUE
J 0
(-4250 4575);
DISPLAY 0.723404 (-4250 4575);
PAINT GREEN (-4250 4575);
DISPLAY INVISIBLE (-4250 4575);
FORCEPROP 2 LAST CDS_LIB pure_quanta
J 0
(-4250 4575);
DISPLAY INVISIBLE (-4250 4575);
FORCEPROP 1 LAST PATH I50
J 0
(-4250 4575);
DISPLAY 0.723404 (-4250 4575);
PAINT GREEN (-4250 4575);
DISPLAY INVISIBLE (-4250 4575);
FORCEADD VCC_CORE..1
(-8900 6575);
FORCEPROP 3 LASTPIN (-8900 6525) SIG_NAME PVDDCR_CPU0_P0\g
J 0
(-8890 6535);
DISPLAY 0.659574 (-8890 6535);
PAINT MONO (-8890 6535);
DISPLAY INVISIBLE (-8890 6535);
FORCEPROP 1 LAST HDL_POWER PVDDCR_CPU0_P0
J 1
(-8900 6625);
DISPLAY 0.489362 (-8900 6625);
PAINT GREEN (-8900 6625);
FORCEPROP 2 LAST CDS_LIB pure_quanta_power
J 0
(-8900 6575);
DISPLAY INVISIBLE (-8900 6575);
FORCEPROP 1 LAST PATH I51
J 0
(-8850 6600);
DISPLAY 0.872340 (-8850 6600);
PAINT AQUA (-8850 6600);
DISPLAY INVISIBLE (-8850 6600);
FORCEADD VCC_CORE..1
(-3300 6600);
FORCEPROP 3 LASTPIN (-3300 6550) SIG_NAME PVDD11_S3_P0\g
J 0
(-3290 6560);
DISPLAY 0.659574 (-3290 6560);
PAINT MONO (-3290 6560);
DISPLAY INVISIBLE (-3290 6560);
FORCEPROP 1 LAST HDL_POWER PVDD11_S3_P0
J 1
(-3300 6650);
DISPLAY 0.489362 (-3300 6650);
PAINT GREEN (-3300 6650);
FORCEPROP 2 LAST CDS_LIB pure_quanta_power
J 0
(-3300 6600);
DISPLAY INVISIBLE (-3300 6600);
FORCEPROP 1 LAST PATH I52
J 0
(-3250 6625);
DISPLAY 0.872340 (-3250 6625);
PAINT AQUA (-3250 6625);
DISPLAY INVISIBLE (-3250 6625);
FORCEADD UNIVERSAL_POWER..1
(-3475 2825);
FORCEPROP 3 LASTPIN (-3475 2775) SIG_NAME PVDD18_S5_P0\g
J 0
(-3465 2785);
DISPLAY 0.659574 (-3465 2785);
PAINT MONO (-3465 2785);
DISPLAY INVISIBLE (-3465 2785);
FORCEPROP 1 LAST HDL_POWER PVDD18_S5_P0
J 1
(-3475 2875);
DISPLAY 0.489362 (-3475 2875);
PAINT GREEN (-3475 2875);
FORCEPROP 2 LAST CDS_LIB pure_quanta_power
J 0
(-3475 2825);
DISPLAY INVISIBLE (-3475 2825);
FORCEPROP 1 LAST PATH I53
J 0
(-3425 2850);
DISPLAY 0.872340 (-3425 2850);
PAINT AQUA (-3425 2850);
DISPLAY INVISIBLE (-3425 2850);
FORCEADD UNIVERSAL_POWER..1
(-3475 1075);
FORCEPROP 3 LASTPIN (-3475 1025) SIG_NAME PVDD_33_S5\g
J 0
(-3465 1035);
DISPLAY 0.659574 (-3465 1035);
PAINT MONO (-3465 1035);
DISPLAY INVISIBLE (-3465 1035);
FORCEPROP 1 LAST HDL_POWER PVDD_33_S5
J 1
(-3475 1125);
DISPLAY 0.489362 (-3475 1125);
PAINT GREEN (-3475 1125);
FORCEPROP 2 LAST CDS_LIB pure_quanta_power
J 0
(-3475 1075);
DISPLAY INVISIBLE (-3475 1075);
FORCEPROP 1 LAST PATH I55
J 0
(-3425 1100);
DISPLAY 0.872340 (-3425 1100);
PAINT AQUA (-3425 1100);
DISPLAY INVISIBLE (-3425 1100);
FORCEADD VCC_CORE..1
(-3500 6150);
FORCEPROP 3 LASTPIN (-3500 6100) SIG_NAME PVDDCR_SOC_P0\g
J 0
(-3490 6110);
DISPLAY 0.659574 (-3490 6110);
PAINT MONO (-3490 6110);
DISPLAY INVISIBLE (-3490 6110);
FORCEPROP 1 LAST HDL_POWER PVDDCR_SOC_P0
J 1
(-3500 6200);
DISPLAY 0.489362 (-3500 6200);
PAINT GREEN (-3500 6200);
FORCEPROP 2 LAST CDS_LIB pure_quanta_power
J 0
(-3500 6150);
DISPLAY INVISIBLE (-3500 6150);
FORCEPROP 1 LAST PATH I56
J 0
(-3450 6175);
DISPLAY 0.872340 (-3450 6175);
PAINT AQUA (-3450 6175);
DISPLAY INVISIBLE (-3450 6175);
FORCEADD VCC_CORE..1
(-4975 6150);
FORCEPROP 3 LASTPIN (-4975 6100) SIG_NAME PVDDCR_SOC_P0\g
J 0
(-4965 6110);
DISPLAY 0.659574 (-4965 6110);
PAINT MONO (-4965 6110);
DISPLAY INVISIBLE (-4965 6110);
FORCEPROP 1 LAST HDL_POWER PVDDCR_SOC_P0
J 1
(-4975 6200);
DISPLAY 0.489362 (-4975 6200);
PAINT GREEN (-4975 6200);
FORCEPROP 2 LAST CDS_LIB pure_quanta_power
J 0
(-4975 6150);
DISPLAY INVISIBLE (-4975 6150);
FORCEPROP 1 LAST PATH I57
J 0
(-4925 6175);
DISPLAY 0.872340 (-4925 6175);
PAINT AQUA (-4925 6175);
DISPLAY INVISIBLE (-4925 6175);
FORCEADD QUANTA_TITLE_BLOCK_C..1
(-100 100);
FORCEPROP 0 LAST CDS_CON_LAST_MODIFIED Fri Mar 11 14:52:24 2022
J 0
(-1985 115);
DISPLAY INVISIBLE (-1985 115);
FORCEPROP 1 LAST CUSTOM_TXT_CDS <CON_LAST_MODIFIED>
J 0
(-1985 115);
DISPLAY 0.978723 (-1985 115);
FORCEPROP 2 LAST CUSTOM_TXT_CDS <XR_PAGE_TITLE>
J 0
(-7990 5350);
DISPLAY 0.638298 (-7990 5350);
PAINT PINK (-7990 5350);
DISPLAY INVISIBLE (-7990 5350);
FORCEPROP 1 LAST CUSTOM_TXT_CDS <NAME_2>
J 0
(-3275 150);
FORCEPROP 1 LAST CUSTOM_TXT_CDS <NAME_1>
J 0
(-3275 275);
FORCEPROP 1 LAST CUSTOM_TXT_CDS <Q_NUMBER>
J 0
(-1503 203);
DISPLAY 1.212766 (-1503 203);
FORCEPROP 1 LAST CUSTOM_TXT_CDS <Q_PROJ>
J 0
(-2482 202);
DISPLAY 1.212766 (-2482 202);
FORCEPROP 1 LAST CUSTOM_TXT_CDS <Q_REV>
J 0
(-284 203);
DISPLAY 1.212766 (-284 203);
FORCEPROP 1 LAST CUSTOM_TXT_CDS <CON_PAGE_NUM> OF <CON_TOTAL_PAGES>
J 0
(-546 118);
DISPLAY 0.978723 (-546 118);
FORCEPROP 1 LAST Q_DEPT BU9
J 1
(-3863 149);
DISPLAY 1.957447 (-3863 149);
PAINT GREEN (-3863 149);
FORCEPROP 1 LAST Q_TITLE CPU0 POWER
J 0
(-9350 175);
DISPLAY 1.574468 (-9350 175);
PAINT GREEN (-9350 175);
FORCEPROP 2 LAST PAGE_BORDER TRUE
J 0
(-7990 5350);
DISPLAY 0.638298 (-7990 5350);
PAINT PINK (-7990 5350);
DISPLAY INVISIBLE (-7990 5350);
FORCEPROP 1 LAST CDS_LMAN_SYM_OUTLINE -9475,6775,100,-125
J 0
(-100 100);
DISPLAY 0.468085 (-100 100);
PAINT GREEN (-100 100);
DISPLAY INVISIBLE (-100 100);
FORCEPROP 2 LAST CDS_LIB pure_quanta
J 0
(-100 100);
DISPLAY INVISIBLE (-100 100);
FORCEPROP 1 LAST COMMENT_BODY TRUE
J 0
(-88 87);
DISPLAY 0.978723 (-88 87);
PAINT GREEN (-88 87);
DISPLAY INVISIBLE (-88 87);
FORCEPROP 2 LAST CDS_XR_PAGE_TITLE CR-30 : @T6G_MB_LIB.T6G(SCH_1):PAGE30
J 0
(-7990 5350);
DISPLAY 0.638298 (-7990 5350);
PAINT PINK (-7990 5350);
DISPLAY INVISIBLE (-7990 5350);
WIRE 16 -1 (-1475 625)(-1475 775);
WIRE 16 -1 (-1825 625)(-1475 625);
WIRE 16 -1 (-8900 575)(-8700 575);
WIRE 16 -1 (-8900 625)(-8900 575);
WIRE 16 -1 (-8900 625)(-8700 625);
WIRE 16 -1 (-8900 675)(-8900 625);
WIRE 16 -1 (-8900 675)(-8700 675);
WIRE 16 -1 (-8900 725)(-8900 675);
WIRE 16 -1 (-8900 725)(-8700 725);
WIRE 16 -1 (-8900 775)(-8900 725);
WIRE 16 -1 (-8900 775)(-8700 775);
WIRE 16 -1 (-8900 825)(-8900 775);
WIRE 16 -1 (-8900 825)(-8700 825);
WIRE 16 -1 (-8900 875)(-8900 825);
WIRE 16 -1 (-8900 875)(-8700 875);
WIRE 16 -1 (-8900 925)(-8900 875);
WIRE 16 -1 (-8900 925)(-8700 925);
WIRE 16 -1 (-8900 975)(-8900 925);
WIRE 16 -1 (-8900 1025)(-8900 975);
WIRE 16 -1 (-8700 975)(-8900 975);
WIRE 16 -1 (-8900 1025)(-8700 1025);
WIRE 16 -1 (-8900 1075)(-8900 1025);
WIRE 16 -1 (-8900 1075)(-8700 1075);
WIRE 16 -1 (-8900 1125)(-8900 1075);
WIRE 16 -1 (-8900 1125)(-8700 1125);
WIRE 16 -1 (-8900 1175)(-8900 1125);
WIRE 16 -1 (-8900 1175)(-8700 1175);
WIRE 16 -1 (-8900 1225)(-8900 1175);
WIRE 16 -1 (-8900 1225)(-8700 1225);
WIRE 16 -1 (-8900 1275)(-8900 1225);
WIRE 16 -1 (-8900 1275)(-8700 1275);
WIRE 16 -1 (-8900 1325)(-8900 1275);
WIRE 16 -1 (-8900 1325)(-8700 1325);
WIRE 16 -1 (-8900 1375)(-8900 1325);
WIRE 16 -1 (-8900 1375)(-8700 1375);
WIRE 16 -1 (-8900 1425)(-8900 1375);
WIRE 16 -1 (-8900 1425)(-8700 1425);
WIRE 16 -1 (-8900 1475)(-8900 1425);
WIRE 16 -1 (-8900 1475)(-8700 1475);
WIRE 16 -1 (-8900 1525)(-8900 1475);
WIRE 16 -1 (-8900 1525)(-8700 1525);
WIRE 16 -1 (-8900 1575)(-8900 1525);
WIRE 16 -1 (-8900 1575)(-8700 1575);
WIRE 16 -1 (-8900 1625)(-8900 1575);
WIRE 16 -1 (-8900 1625)(-8700 1625);
WIRE 16 -1 (-8900 1675)(-8900 1625);
WIRE 16 -1 (-8900 1675)(-8700 1675);
WIRE 16 -1 (-8900 1725)(-8900 1675);
WIRE 16 -1 (-8900 1725)(-8700 1725);
WIRE 16 -1 (-8900 1775)(-8900 1725);
WIRE 16 -1 (-8900 1775)(-8700 1775);
WIRE 16 -1 (-8900 1825)(-8900 1775);
WIRE 16 -1 (-8900 1825)(-8700 1825);
WIRE 16 -1 (-8900 1875)(-8900 1825);
WIRE 16 -1 (-8900 1875)(-8700 1875);
WIRE 16 -1 (-8900 1925)(-8900 1875);
WIRE 16 -1 (-8900 1925)(-8700 1925);
WIRE 16 -1 (-8900 1975)(-8900 1925);
WIRE 16 -1 (-8900 1975)(-8700 1975);
WIRE 16 -1 (-8900 2025)(-8900 1975);
WIRE 16 -1 (-8900 2075)(-8900 2025);
WIRE 16 -1 (-8700 2025)(-8900 2025);
WIRE 16 -1 (-8900 2075)(-8700 2075);
WIRE 16 -1 (-8900 2125)(-8900 2075);
WIRE 16 -1 (-8900 2125)(-8700 2125);
WIRE 16 -1 (-8900 2175)(-8900 2125);
WIRE 16 -1 (-8900 2175)(-8700 2175);
WIRE 16 -1 (-8900 2225)(-8900 2175);
WIRE 16 -1 (-8900 2225)(-8700 2225);
WIRE 16 -1 (-8900 2275)(-8900 2225);
WIRE 16 -1 (-8900 2275)(-8700 2275);
WIRE 16 -1 (-8900 2325)(-8900 2275);
WIRE 16 -1 (-8900 2325)(-8700 2325);
WIRE 16 -1 (-8900 2375)(-8900 2325);
WIRE 16 -1 (-8900 2375)(-8700 2375);
WIRE 16 -1 (-8900 2425)(-8900 2375);
WIRE 16 -1 (-8900 2425)(-8700 2425);
WIRE 16 -1 (-8900 2475)(-8900 2425);
WIRE 16 -1 (-8900 2475)(-8700 2475);
WIRE 16 -1 (-8900 2525)(-8900 2475);
WIRE 16 -1 (-8900 2525)(-8700 2525);
WIRE 16 -1 (-8900 2575)(-8900 2525);
WIRE 16 -1 (-8900 2575)(-8700 2575);
WIRE 16 -1 (-8900 2625)(-8900 2575);
WIRE 16 -1 (-8900 2625)(-8700 2625);
WIRE 16 -1 (-8900 2675)(-8900 2625);
WIRE 16 -1 (-8900 2675)(-8700 2675);
WIRE 16 -1 (-8900 2725)(-8900 2675);
WIRE 16 -1 (-8900 2725)(-8700 2725);
WIRE 16 -1 (-8900 2775)(-8900 2725);
WIRE 16 -1 (-8900 2775)(-8700 2775);
WIRE 16 -1 (-8900 2825)(-8900 2775);
WIRE 16 -1 (-8900 2825)(-8700 2825);
WIRE 16 -1 (-8900 2875)(-8900 2825);
WIRE 16 -1 (-8900 2875)(-8700 2875);
WIRE 16 -1 (-8900 2925)(-8900 2875);
WIRE 16 -1 (-8900 2925)(-8700 2925);
WIRE 16 -1 (-8900 2975)(-8900 2925);
WIRE 16 -1 (-8900 2975)(-8700 2975);
WIRE 16 -1 (-8900 3025)(-8900 2975);
WIRE 16 -1 (-8900 3075)(-8900 3025);
WIRE 16 -1 (-8700 3025)(-8900 3025);
WIRE 16 -1 (-8900 3075)(-8700 3075);
WIRE 16 -1 (-8900 3125)(-8900 3075);
WIRE 16 -1 (-8900 3125)(-8700 3125);
WIRE 16 -1 (-8900 3175)(-8900 3125);
WIRE 16 -1 (-8900 3175)(-8700 3175);
WIRE 16 -1 (-8900 3225)(-8900 3175);
WIRE 16 -1 (-8900 3225)(-8700 3225);
WIRE 16 -1 (-8900 3275)(-8900 3225);
WIRE 16 -1 (-8900 3275)(-8700 3275);
WIRE 16 -1 (-8900 3325)(-8900 3275);
WIRE 16 -1 (-8900 3325)(-8700 3325);
WIRE 16 -1 (-8900 3375)(-8900 3325);
WIRE 16 -1 (-8900 3375)(-8700 3375);
WIRE 16 -1 (-8900 3425)(-8900 3375);
WIRE 16 -1 (-8900 3425)(-8700 3425);
WIRE 16 -1 (-8900 3475)(-8900 3425);
WIRE 16 -1 (-8900 3475)(-8700 3475);
WIRE 16 -1 (-8900 3525)(-8900 3475);
WIRE 16 -1 (-8900 3525)(-8700 3525);
WIRE 16 -1 (-8900 3575)(-8900 3525);
WIRE 16 -1 (-8900 3575)(-8700 3575);
WIRE 16 -1 (-8900 3625)(-8900 3575);
WIRE 16 -1 (-8900 3625)(-8700 3625);
WIRE 16 -1 (-8900 3675)(-8900 3625);
WIRE 16 -1 (-8900 3675)(-8700 3675);
WIRE 16 -1 (-8900 3725)(-8900 3675);
WIRE 16 -1 (-8900 3725)(-8700 3725);
WIRE 16 -1 (-8900 3775)(-8900 3725);
WIRE 16 -1 (-8900 3775)(-8700 3775);
WIRE 16 -1 (-8900 3825)(-8900 3775);
WIRE 16 -1 (-8900 3825)(-8700 3825);
WIRE 16 -1 (-8900 3875)(-8900 3825);
WIRE 16 -1 (-8900 3875)(-8700 3875);
WIRE 16 -1 (-8900 3925)(-8900 3875);
WIRE 16 -1 (-8900 3925)(-8700 3925);
WIRE 16 -1 (-8900 3975)(-8900 3925);
WIRE 16 -1 (-8900 3975)(-8700 3975);
WIRE 16 -1 (-8900 4025)(-8900 3975);
WIRE 16 -1 (-8900 4025)(-8700 4025);
WIRE 16 -1 (-8900 4075)(-8900 4025);
WIRE 16 -1 (-8900 4125)(-8900 4075);
WIRE 16 -1 (-8700 4075)(-8900 4075);
WIRE 16 -1 (-8900 4125)(-8700 4125);
WIRE 16 -1 (-8900 4175)(-8900 4125);
WIRE 16 -1 (-8900 4175)(-8700 4175);
WIRE 16 -1 (-8900 4225)(-8900 4175);
WIRE 16 -1 (-8900 4225)(-8700 4225);
WIRE 16 -1 (-8900 4275)(-8900 4225);
WIRE 16 -1 (-8900 4275)(-8700 4275);
WIRE 16 -1 (-8900 4325)(-8900 4275);
WIRE 16 -1 (-8900 4325)(-8700 4325);
WIRE 16 -1 (-8900 4375)(-8900 4325);
WIRE 16 -1 (-8900 4375)(-8700 4375);
WIRE 16 -1 (-8900 4425)(-8900 4375);
WIRE 16 -1 (-8900 4425)(-8700 4425);
WIRE 16 -1 (-8900 4475)(-8900 4425);
WIRE 16 -1 (-8900 4475)(-8700 4475);
WIRE 16 -1 (-8900 4525)(-8900 4475);
WIRE 16 -1 (-8900 4525)(-8700 4525);
WIRE 16 -1 (-8900 4575)(-8900 4525);
WIRE 16 -1 (-8900 4575)(-8700 4575);
WIRE 16 -1 (-8900 4625)(-8900 4575);
WIRE 16 -1 (-8900 4625)(-8700 4625);
WIRE 16 -1 (-8900 4675)(-8900 4625);
WIRE 16 -1 (-8900 4675)(-8700 4675);
WIRE 16 -1 (-8900 4725)(-8900 4675);
WIRE 16 -1 (-8900 4725)(-8700 4725);
WIRE 16 -1 (-8900 4775)(-8900 4725);
WIRE 16 -1 (-8900 4775)(-8700 4775);
WIRE 16 -1 (-8900 4825)(-8900 4775);
WIRE 16 -1 (-8900 4825)(-8700 4825);
WIRE 16 -1 (-8900 4875)(-8900 4825);
WIRE 16 -1 (-8900 4875)(-8700 4875);
WIRE 16 -1 (-8900 4925)(-8900 4875);
WIRE 16 -1 (-8900 4925)(-8700 4925);
WIRE 16 -1 (-8900 4975)(-8900 4925);
WIRE 16 -1 (-8900 4975)(-8700 4975);
WIRE 16 -1 (-8900 5025)(-8900 4975);
WIRE 16 -1 (-8900 5025)(-8700 5025);
WIRE 16 -1 (-8900 5075)(-8900 5025);
WIRE 16 -1 (-8900 5125)(-8900 5075);
WIRE 16 -1 (-8700 5075)(-8900 5075);
WIRE 16 -1 (-8900 5125)(-8700 5125);
WIRE 16 -1 (-8900 5175)(-8900 5125);
WIRE 16 -1 (-8900 5175)(-8700 5175);
WIRE 16 -1 (-8900 5225)(-8900 5175);
WIRE 16 -1 (-8900 5225)(-8700 5225);
WIRE 16 -1 (-8900 5275)(-8900 5225);
WIRE 16 -1 (-8900 5275)(-8700 5275);
WIRE 16 -1 (-8900 5325)(-8900 5275);
WIRE 16 -1 (-8900 5325)(-8700 5325);
WIRE 16 -1 (-8900 5375)(-8900 5325);
WIRE 16 -1 (-8900 5375)(-8700 5375);
WIRE 16 -1 (-8900 5425)(-8900 5375);
WIRE 16 -1 (-8900 5425)(-8700 5425);
WIRE 16 -1 (-8900 5475)(-8900 5425);
WIRE 16 -1 (-8900 5475)(-8700 5475);
WIRE 16 -1 (-8900 5525)(-8900 5475);
WIRE 16 -1 (-8900 5525)(-8700 5525);
WIRE 16 -1 (-8900 5575)(-8900 5525);
WIRE 16 -1 (-8900 5575)(-8700 5575);
WIRE 16 -1 (-8900 5625)(-8900 5575);
WIRE 16 -1 (-8900 5625)(-8700 5625);
WIRE 16 -1 (-8900 5675)(-8900 5625);
WIRE 16 -1 (-8900 5675)(-8700 5675);
WIRE 16 -1 (-8900 5725)(-8900 5675);
WIRE 16 -1 (-8900 5725)(-8700 5725);
WIRE 16 -1 (-8900 5775)(-8900 5725);
WIRE 16 -1 (-8900 5775)(-8700 5775);
WIRE 16 -1 (-8900 5825)(-8900 5775);
WIRE 16 -1 (-8900 5825)(-8700 5825);
WIRE 16 -1 (-8900 5875)(-8900 5825);
WIRE 16 -1 (-8900 5875)(-8700 5875);
WIRE 16 -1 (-8900 5925)(-8900 5875);
WIRE 16 -1 (-8900 5925)(-8700 5925);
WIRE 16 -1 (-8900 5975)(-8900 5925);
WIRE 16 -1 (-8900 5975)(-8700 5975);
WIRE 16 -1 (-8900 6025)(-8900 5975);
WIRE 16 -1 (-8900 6025)(-8700 6025);
WIRE 16 -1 (-8900 6075)(-8900 6025);
WIRE 16 -1 (-8900 6075)(-8700 6075);
WIRE 16 -1 (-8900 6125)(-8900 6075);
WIRE 16 -1 (-8900 6175)(-8900 6125);
WIRE 16 -1 (-8700 6125)(-8900 6125);
WIRE 16 -1 (-8900 6175)(-8700 6175);
WIRE 16 -1 (-8900 6225)(-8900 6175);
WIRE 16 -1 (-8900 6225)(-8700 6225);
WIRE 16 -1 (-8900 6275)(-8900 6225);
WIRE 16 -1 (-8900 6275)(-8700 6275);
WIRE 16 -1 (-8900 6325)(-8900 6275);
WIRE 16 -1 (-8900 6325)(-8700 6325);
WIRE 16 -1 (-8900 6525)(-8900 6325);
WIRE 16 -1 (-7400 525)(-7250 525);
WIRE 16 -1 (-7250 575)(-7250 525);
WIRE 16 -1 (-7400 575)(-7250 575);
WIRE 16 -1 (-7250 625)(-7250 575);
WIRE 16 -1 (-7400 625)(-7250 625);
WIRE 16 -1 (-7250 675)(-7250 625);
WIRE 16 -1 (-7400 675)(-7250 675);
WIRE 16 -1 (-7250 725)(-7250 675);
WIRE 16 -1 (-7400 725)(-7250 725);
WIRE 16 -1 (-7250 775)(-7250 725);
WIRE 16 -1 (-7250 825)(-7250 775);
WIRE 16 -1 (-7400 775)(-7250 775);
WIRE 16 -1 (-7400 825)(-7250 825);
WIRE 16 -1 (-7250 875)(-7250 825);
WIRE 16 -1 (-7400 875)(-7250 875);
WIRE 16 -1 (-7250 875)(-7250 925);
WIRE 16 -1 (-7400 925)(-7250 925);
WIRE 16 -1 (-7250 975)(-7250 925);
WIRE 16 -1 (-7400 975)(-7250 975);
WIRE 16 -1 (-7250 1025)(-7250 975);
WIRE 16 -1 (-7250 1075)(-7250 1025);
WIRE 16 -1 (-7400 1025)(-7250 1025);
WIRE 16 -1 (-7400 1075)(-7250 1075);
WIRE 16 -1 (-7250 1125)(-7250 1075);
WIRE 16 -1 (-7400 1125)(-7250 1125);
WIRE 16 -1 (-7250 1175)(-7250 1125);
WIRE 16 -1 (-7400 1175)(-7250 1175);
WIRE 16 -1 (-7250 1225)(-7250 1175);
WIRE 16 -1 (-7400 1225)(-7250 1225);
WIRE 16 -1 (-7250 1275)(-7250 1225);
WIRE 16 -1 (-7400 1275)(-7250 1275);
WIRE 16 -1 (-7250 1325)(-7250 1275);
WIRE 16 -1 (-7250 1325)(-7250 1375);
WIRE 16 -1 (-7400 1325)(-7250 1325);
WIRE 16 -1 (-7400 1375)(-7250 1375);
WIRE 16 -1 (-7250 1425)(-7250 1375);
WIRE 16 -1 (-7400 1425)(-7250 1425);
WIRE 16 -1 (-7250 1475)(-7250 1425);
WIRE 16 -1 (-7400 1475)(-7250 1475);
WIRE 16 -1 (-7250 1525)(-7250 1475);
WIRE 16 -1 (-7400 1525)(-7250 1525);
WIRE 16 -1 (-7250 1575)(-7250 1525);
WIRE 16 -1 (-7250 1625)(-7250 1575);
WIRE 16 -1 (-7400 1575)(-7250 1575);
WIRE 16 -1 (-7400 1625)(-7250 1625);
WIRE 16 -1 (-7250 1675)(-7250 1625);
WIRE 16 -1 (-7400 1675)(-7250 1675);
WIRE 16 -1 (-7250 1725)(-7250 1675);
WIRE 16 -1 (-7400 1725)(-7250 1725);
WIRE 16 -1 (-7250 1775)(-7250 1725);
WIRE 16 -1 (-7400 1775)(-7250 1775);
WIRE 16 -1 (-7250 1775)(-7250 1825);
WIRE 16 -1 (-7250 1875)(-7250 1825);
WIRE 16 -1 (-7400 1825)(-7250 1825);
WIRE 16 -1 (-7400 1875)(-7250 1875);
WIRE 16 -1 (-7250 1925)(-7250 1875);
WIRE 16 -1 (-7400 1925)(-7250 1925);
WIRE 16 -1 (-7250 1975)(-7250 1925);
WIRE 16 -1 (-7400 1975)(-7250 1975);
WIRE 16 -1 (-7250 2025)(-7250 1975);
WIRE 16 -1 (-7400 2025)(-7250 2025);
WIRE 16 -1 (-7250 2075)(-7250 2025);
WIRE 16 -1 (-7250 2125)(-7250 2075);
WIRE 16 -1 (-7400 2075)(-7250 2075);
WIRE 16 -1 (-7400 2125)(-7250 2125);
WIRE 16 -1 (-7250 2175)(-7250 2125);
WIRE 16 -1 (-7400 2175)(-7250 2175);
WIRE 16 -1 (-7250 2225)(-7250 2175);
WIRE 16 -1 (-7400 2225)(-7250 2225);
WIRE 16 -1 (-7250 2225)(-7250 2275);
WIRE 16 -1 (-7400 2275)(-7250 2275);
WIRE 16 -1 (-7250 2325)(-7250 2275);
WIRE 16 -1 (-7250 2375)(-7250 2325);
WIRE 16 -1 (-7400 2325)(-7250 2325);
WIRE 16 -1 (-7400 2375)(-7250 2375);
WIRE 16 -1 (-7250 2425)(-7250 2375);
WIRE 16 -1 (-7400 2425)(-7250 2425);
WIRE 16 -1 (-7250 2475)(-7250 2425);
WIRE 16 -1 (-7400 2475)(-7250 2475);
WIRE 16 -1 (-7250 2525)(-7250 2475);
WIRE 16 -1 (-7400 2525)(-7250 2525);
WIRE 16 -1 (-7250 2575)(-7250 2525);
WIRE 16 -1 (-7250 2625)(-7250 2575);
WIRE 16 -1 (-7400 2575)(-7250 2575);
WIRE 16 -1 (-7400 2625)(-7250 2625);
WIRE 16 -1 (-7250 2675)(-7250 2625);
WIRE 16 -1 (-7400 2675)(-7250 2675);
WIRE 16 -1 (-7250 2675)(-7250 2725);
WIRE 16 -1 (-7400 2725)(-7250 2725);
WIRE 16 -1 (-7250 2775)(-7250 2725);
WIRE 16 -1 (-7400 2775)(-7250 2775);
WIRE 16 -1 (-7250 2825)(-7250 2775);
WIRE 16 -1 (-7250 2875)(-7250 2825);
WIRE 16 -1 (-7400 2825)(-7250 2825);
WIRE 16 -1 (-7400 2875)(-7250 2875);
WIRE 16 -1 (-7250 2925)(-7250 2875);
WIRE 16 -1 (-7400 2925)(-7250 2925);
WIRE 16 -1 (-7250 2975)(-7250 2925);
WIRE 16 -1 (-7400 2975)(-7250 2975);
WIRE 16 -1 (-7250 3025)(-7250 2975);
WIRE 16 -1 (-7400 3025)(-7250 3025);
WIRE 16 -1 (-7250 3075)(-7250 3025);
WIRE 16 -1 (-7250 3125)(-7250 3075);
WIRE 16 -1 (-7400 3075)(-7250 3075);
WIRE 16 -1 (-7400 3125)(-7250 3125);
WIRE 16 -1 (-7250 3125)(-7250 3175);
WIRE 16 -1 (-7400 3175)(-7250 3175);
WIRE 16 -1 (-7250 3225)(-7250 3175);
WIRE 16 -1 (-7400 3225)(-7250 3225);
WIRE 16 -1 (-7250 3275)(-7250 3225);
WIRE 16 -1 (-7400 3275)(-7250 3275);
WIRE 16 -1 (-7250 3325)(-7250 3275);
WIRE 16 -1 (-7400 3325)(-7250 3325);
WIRE 16 -1 (-7250 3375)(-7250 3325);
WIRE 16 -1 (-7250 3425)(-7250 3375);
WIRE 16 -1 (-7400 3375)(-7250 3375);
WIRE 16 -1 (-7400 3425)(-7250 3425);
WIRE 16 -1 (-7250 3475)(-7250 3425);
WIRE 16 -1 (-7400 3475)(-7250 3475);
WIRE 16 -1 (-7250 3525)(-7250 3475);
WIRE 16 -1 (-7400 3525)(-7250 3525);
WIRE 16 -1 (-7250 3575)(-7250 3525);
WIRE 16 -1 (-7400 3575)(-7250 3575);
WIRE 16 -1 (-7250 3575)(-7250 3625);
WIRE 16 -1 (-7250 3675)(-7250 3625);
WIRE 16 -1 (-7400 3625)(-7250 3625);
WIRE 16 -1 (-7400 3675)(-7250 3675);
WIRE 16 -1 (-7250 3725)(-7250 3675);
WIRE 16 -1 (-7400 3725)(-7250 3725);
WIRE 16 -1 (-7250 3775)(-7250 3725);
WIRE 16 -1 (-7400 3775)(-7250 3775);
WIRE 16 -1 (-7250 3825)(-7250 3775);
WIRE 16 -1 (-7400 3825)(-7250 3825);
WIRE 16 -1 (-7250 3875)(-7250 3825);
WIRE 16 -1 (-7250 3925)(-7250 3875);
WIRE 16 -1 (-7400 3875)(-7250 3875);
WIRE 16 -1 (-7400 3925)(-7250 3925);
WIRE 16 -1 (-7250 3975)(-7250 3925);
WIRE 16 -1 (-7400 3975)(-7250 3975);
WIRE 16 -1 (-7250 4025)(-7250 3975);
WIRE 16 -1 (-7400 4025)(-7250 4025);
WIRE 16 -1 (-7250 4025)(-7250 4075);
WIRE 16 -1 (-7400 4075)(-7250 4075);
WIRE 16 -1 (-7250 4125)(-7250 4075);
WIRE 16 -1 (-7250 4175)(-7250 4125);
WIRE 16 -1 (-7400 4125)(-7250 4125);
WIRE 16 -1 (-7400 4175)(-7250 4175);
WIRE 16 -1 (-7250 4225)(-7250 4175);
WIRE 16 -1 (-7400 4225)(-7250 4225);
WIRE 16 -1 (-7250 4275)(-7250 4225);
WIRE 16 -1 (-7400 4275)(-7250 4275);
WIRE 16 -1 (-7250 4325)(-7250 4275);
WIRE 16 -1 (-7400 4325)(-7250 4325);
WIRE 16 -1 (-7250 4375)(-7250 4325);
WIRE 16 -1 (-7250 4425)(-7250 4375);
WIRE 16 -1 (-7400 4375)(-7250 4375);
WIRE 16 -1 (-7400 4425)(-7250 4425);
WIRE 16 -1 (-7250 4475)(-7250 4425);
WIRE 16 -1 (-7400 4475)(-7250 4475);
WIRE 16 -1 (-7250 4475)(-7250 4525);
WIRE 16 -1 (-7400 4525)(-7250 4525);
WIRE 16 -1 (-7250 4575)(-7250 4525);
WIRE 16 -1 (-7400 4575)(-7250 4575);
WIRE 16 -1 (-7250 4625)(-7250 4575);
WIRE 16 -1 (-7250 4675)(-7250 4625);
WIRE 16 -1 (-7400 4625)(-7250 4625);
WIRE 16 -1 (-7400 4675)(-7250 4675);
WIRE 16 -1 (-7250 4725)(-7250 4675);
WIRE 16 -1 (-7400 4725)(-7250 4725);
WIRE 16 -1 (-7250 4775)(-7250 4725);
WIRE 16 -1 (-7400 4775)(-7250 4775);
WIRE 16 -1 (-7250 4825)(-7250 4775);
WIRE 16 -1 (-7400 4825)(-7250 4825);
WIRE 16 -1 (-7250 4875)(-7250 4825);
WIRE 16 -1 (-7250 4925)(-7250 4875);
WIRE 16 -1 (-7400 4875)(-7250 4875);
WIRE 16 -1 (-7400 4925)(-7250 4925);
WIRE 16 -1 (-7250 4925)(-7250 4975);
WIRE 16 -1 (-7400 4975)(-7250 4975);
WIRE 16 -1 (-7250 5025)(-7250 4975);
WIRE 16 -1 (-7400 5025)(-7250 5025);
WIRE 16 -1 (-7250 5075)(-7250 5025);
WIRE 16 -1 (-7400 5075)(-7250 5075);
WIRE 16 -1 (-7250 5125)(-7250 5075);
WIRE 16 -1 (-7250 5175)(-7250 5125);
WIRE 16 -1 (-7400 5125)(-7250 5125);
WIRE 16 -1 (-7400 5175)(-7250 5175);
WIRE 16 -1 (-7250 5225)(-7250 5175);
WIRE 16 -1 (-7400 5225)(-7250 5225);
WIRE 16 -1 (-7250 5275)(-7250 5225);
WIRE 16 -1 (-7400 5275)(-7250 5275);
WIRE 16 -1 (-7250 5325)(-7250 5275);
WIRE 16 -1 (-7400 5325)(-7250 5325);
WIRE 16 -1 (-7250 5375)(-7250 5325);
WIRE 16 -1 (-7400 5375)(-7250 5375);
WIRE 16 -1 (-7250 5375)(-7250 5425);
WIRE 16 -1 (-7250 5475)(-7250 5425);
WIRE 16 -1 (-7400 5425)(-7250 5425);
WIRE 16 -1 (-7400 5475)(-7250 5475);
WIRE 16 -1 (-7250 5525)(-7250 5475);
WIRE 16 -1 (-7400 5525)(-7250 5525);
WIRE 16 -1 (-7250 5575)(-7250 5525);
WIRE 16 -1 (-7400 5575)(-7250 5575);
WIRE 16 -1 (-7250 5625)(-7250 5575);
WIRE 16 -1 (-7400 5625)(-7250 5625);
WIRE 16 -1 (-7250 5675)(-7250 5625);
WIRE 16 -1 (-7250 5725)(-7250 5675);
WIRE 16 -1 (-7400 5675)(-7250 5675);
WIRE 16 -1 (-7400 5725)(-7250 5725);
WIRE 16 -1 (-7250 5775)(-7250 5725);
WIRE 16 -1 (-7400 5775)(-7250 5775);
WIRE 16 -1 (-7250 5825)(-7250 5775);
WIRE 16 -1 (-7400 5825)(-7250 5825);
WIRE 16 -1 (-7250 5825)(-7250 5875);
WIRE 16 -1 (-7400 5875)(-7250 5875);
WIRE 16 -1 (-7250 5925)(-7250 5875);
WIRE 16 -1 (-7250 5975)(-7250 5925);
WIRE 16 -1 (-7400 5925)(-7250 5925);
WIRE 16 -1 (-7400 5975)(-7250 5975);
WIRE 16 -1 (-7250 6025)(-7250 5975);
WIRE 16 -1 (-7400 6025)(-7250 6025);
WIRE 16 -1 (-7250 6075)(-7250 6025);
WIRE 16 -1 (-7400 6075)(-7250 6075);
WIRE 16 -1 (-7250 6125)(-7250 6075);
WIRE 16 -1 (-7400 6125)(-7250 6125);
WIRE 16 -1 (-7250 6175)(-7250 6125);
WIRE 16 -1 (-7250 6225)(-7250 6175);
WIRE 16 -1 (-7400 6175)(-7250 6175);
WIRE 16 -1 (-7400 6225)(-7250 6225);
WIRE 16 -1 (-7250 6275)(-7250 6225);
WIRE 16 -1 (-7400 6275)(-7250 6275);
WIRE 16 -1 (-7250 6275)(-7250 6325);
WIRE 16 -1 (-7250 6525)(-7250 6325);
WIRE 16 -1 (-7400 6325)(-7250 6325);
WIRE 16 -1 (-6900 700)(-6725 700);
WIRE 16 -1 (-6900 750)(-6900 700);
WIRE 16 -1 (-6900 800)(-6900 750);
WIRE 16 -1 (-6900 750)(-6725 750);
WIRE 16 -1 (-6900 800)(-6725 800);
WIRE 16 -1 (-6900 850)(-6900 800);
WIRE 16 -1 (-6725 850)(-6900 850);
WIRE 16 -1 (-6900 900)(-6900 850);
WIRE 16 -1 (-6900 900)(-6725 900);
WIRE 16 -1 (-6900 950)(-6900 900);
WIRE 16 -1 (-6900 950)(-6725 950);
WIRE 16 -1 (-6900 1000)(-6900 950);
WIRE 16 -1 (-6900 1050)(-6900 1000);
WIRE 16 -1 (-6900 1000)(-6725 1000);
WIRE 16 -1 (-6900 1050)(-6725 1050);
WIRE 16 -1 (-6900 1100)(-6900 1050);
WIRE 16 -1 (-6900 1100)(-6725 1100);
WIRE 16 -1 (-6900 1150)(-6900 1100);
WIRE 16 -1 (-6725 1150)(-6900 1150);
WIRE 16 -1 (-6900 1200)(-6900 1150);
WIRE 16 -1 (-6900 1200)(-6725 1200);
WIRE 16 -1 (-6900 1250)(-6900 1200);
WIRE 16 -1 (-6900 1300)(-6900 1250);
WIRE 16 -1 (-6900 1250)(-6725 1250);
WIRE 16 -1 (-6900 1300)(-6725 1300);
WIRE 16 -1 (-6900 1350)(-6900 1300);
WIRE 16 -1 (-6900 1350)(-6725 1350);
WIRE 16 -1 (-6900 1400)(-6900 1350);
WIRE 16 -1 (-6725 1400)(-6900 1400);
WIRE 16 -1 (-6900 1450)(-6900 1400);
WIRE 16 -1 (-6900 1450)(-6725 1450);
WIRE 16 -1 (-6900 1500)(-6900 1450);
WIRE 16 -1 (-6900 1550)(-6900 1500);
WIRE 16 -1 (-6900 1500)(-6725 1500);
WIRE 16 -1 (-6900 1550)(-6725 1550);
WIRE 16 -1 (-6900 1600)(-6900 1550);
WIRE 16 -1 (-6900 1600)(-6725 1600);
WIRE 16 -1 (-6900 1650)(-6900 1600);
WIRE 16 -1 (-6725 1650)(-6900 1650);
WIRE 16 -1 (-6900 1700)(-6900 1650);
WIRE 16 -1 (-6900 1700)(-6725 1700);
WIRE 16 -1 (-6900 1750)(-6900 1700);
WIRE 16 -1 (-6900 1800)(-6900 1750);
WIRE 16 -1 (-6900 1750)(-6725 1750);
WIRE 16 -1 (-6900 1800)(-6725 1800);
WIRE 16 -1 (-6900 1850)(-6900 1800);
WIRE 16 -1 (-6900 1850)(-6725 1850);
WIRE 16 -1 (-6900 1900)(-6900 1850);
WIRE 16 -1 (-6725 1900)(-6900 1900);
WIRE 16 -1 (-6900 1950)(-6900 1900);
WIRE 16 -1 (-6900 1950)(-6725 1950);
WIRE 16 -1 (-6900 2000)(-6900 1950);
WIRE 16 -1 (-6900 2050)(-6900 2000);
WIRE 16 -1 (-6900 2000)(-6725 2000);
WIRE 16 -1 (-6900 2050)(-6725 2050);
WIRE 16 -1 (-6900 2100)(-6900 2050);
WIRE 16 -1 (-6900 2100)(-6725 2100);
WIRE 16 -1 (-6900 2150)(-6900 2100);
WIRE 16 -1 (-6725 2150)(-6900 2150);
WIRE 16 -1 (-6900 2200)(-6900 2150);
WIRE 16 -1 (-6900 2200)(-6725 2200);
WIRE 16 -1 (-6900 2250)(-6900 2200);
WIRE 16 -1 (-6900 2250)(-6725 2250);
WIRE 16 -1 (-6900 2300)(-6900 2250);
WIRE 16 -1 (-6900 2350)(-6900 2300);
WIRE 16 -1 (-6900 2300)(-6725 2300);
WIRE 16 -1 (-6900 2350)(-6725 2350);
WIRE 16 -1 (-6900 2400)(-6900 2350);
WIRE 16 -1 (-6725 2400)(-6900 2400);
WIRE 16 -1 (-6900 2450)(-6900 2400);
WIRE 16 -1 (-6900 2450)(-6725 2450);
WIRE 16 -1 (-6900 2500)(-6900 2450);
WIRE 16 -1 (-6900 2500)(-6725 2500);
WIRE 16 -1 (-6900 2550)(-6900 2500);
WIRE 16 -1 (-6900 2600)(-6900 2550);
WIRE 16 -1 (-6900 2550)(-6725 2550);
WIRE 16 -1 (-6900 2600)(-6725 2600);
WIRE 16 -1 (-6900 2650)(-6900 2600);
WIRE 16 -1 (-6725 2650)(-6900 2650);
WIRE 16 -1 (-6900 2700)(-6900 2650);
WIRE 16 -1 (-6900 2700)(-6725 2700);
WIRE 16 -1 (-6900 2750)(-6900 2700);
WIRE 16 -1 (-6900 2750)(-6725 2750);
WIRE 16 -1 (-6900 2800)(-6900 2750);
WIRE 16 -1 (-6900 2850)(-6900 2800);
WIRE 16 -1 (-6900 2800)(-6725 2800);
WIRE 16 -1 (-6900 2850)(-6725 2850);
WIRE 16 -1 (-6900 2900)(-6900 2850);
WIRE 16 -1 (-6725 2900)(-6900 2900);
WIRE 16 -1 (-6900 2950)(-6900 2900);
WIRE 16 -1 (-6900 2950)(-6725 2950);
WIRE 16 -1 (-6900 3000)(-6900 2950);
WIRE 16 -1 (-6900 3000)(-6725 3000);
WIRE 16 -1 (-6900 3050)(-6900 3000);
WIRE 16 -1 (-6900 3100)(-6900 3050);
WIRE 16 -1 (-6900 3050)(-6725 3050);
WIRE 16 -1 (-6900 3100)(-6725 3100);
WIRE 16 -1 (-6900 3150)(-6900 3100);
WIRE 16 -1 (-6900 3150)(-6725 3150);
WIRE 16 -1 (-6900 3200)(-6900 3150);
WIRE 16 -1 (-6725 3200)(-6900 3200);
WIRE 16 -1 (-6900 3250)(-6900 3200);
WIRE 16 -1 (-6900 3250)(-6725 3250);
WIRE 16 -1 (-6900 3300)(-6900 3250);
WIRE 16 -1 (-6900 3350)(-6900 3300);
WIRE 16 -1 (-6900 3300)(-6725 3300);
WIRE 16 -1 (-6900 3350)(-6725 3350);
WIRE 16 -1 (-6900 3400)(-6900 3350);
WIRE 16 -1 (-6900 3400)(-6725 3400);
WIRE 16 -1 (-6900 3450)(-6900 3400);
WIRE 16 -1 (-6725 3450)(-6900 3450);
WIRE 16 -1 (-6900 3500)(-6900 3450);
WIRE 16 -1 (-6900 3500)(-6725 3500);
WIRE 16 -1 (-6900 3550)(-6900 3500);
WIRE 16 -1 (-6900 3600)(-6900 3550);
WIRE 16 -1 (-6900 3550)(-6725 3550);
WIRE 16 -1 (-6900 3600)(-6725 3600);
WIRE 16 -1 (-6900 3650)(-6900 3600);
WIRE 16 -1 (-6900 3650)(-6725 3650);
WIRE 16 -1 (-6900 3700)(-6900 3650);
WIRE 16 -1 (-6725 3700)(-6900 3700);
WIRE 16 -1 (-6900 3750)(-6900 3700);
WIRE 16 -1 (-6900 3750)(-6725 3750);
WIRE 16 -1 (-6900 3800)(-6900 3750);
WIRE 16 -1 (-6900 3850)(-6900 3800);
WIRE 16 -1 (-6900 3800)(-6725 3800);
WIRE 16 -1 (-6900 3850)(-6725 3850);
WIRE 16 -1 (-6900 3900)(-6900 3850);
WIRE 16 -1 (-6900 3900)(-6725 3900);
WIRE 16 -1 (-6900 3950)(-6900 3900);
WIRE 16 -1 (-6725 3950)(-6900 3950);
WIRE 16 -1 (-6900 4000)(-6900 3950);
WIRE 16 -1 (-6900 4000)(-6725 4000);
WIRE 16 -1 (-6900 4050)(-6900 4000);
WIRE 16 -1 (-6900 4100)(-6900 4050);
WIRE 16 -1 (-6900 4050)(-6725 4050);
WIRE 16 -1 (-6900 4100)(-6725 4100);
WIRE 16 -1 (-6900 4150)(-6900 4100);
WIRE 16 -1 (-6900 4150)(-6725 4150);
WIRE 16 -1 (-6900 4200)(-6900 4150);
WIRE 16 -1 (-6725 4200)(-6900 4200);
WIRE 16 -1 (-6900 4250)(-6900 4200);
WIRE 16 -1 (-6900 4250)(-6725 4250);
WIRE 16 -1 (-6900 4300)(-6900 4250);
WIRE 16 -1 (-6900 4300)(-6725 4300);
WIRE 16 -1 (-6900 4350)(-6900 4300);
WIRE 16 -1 (-6900 4400)(-6900 4350);
WIRE 16 -1 (-6900 4350)(-6725 4350);
WIRE 16 -1 (-6900 4400)(-6725 4400);
WIRE 16 -1 (-6900 4450)(-6900 4400);
WIRE 16 -1 (-6725 4450)(-6900 4450);
WIRE 16 -1 (-6900 4500)(-6900 4450);
WIRE 16 -1 (-6900 4500)(-6725 4500);
WIRE 16 -1 (-6900 4550)(-6900 4500);
WIRE 16 -1 (-6900 4550)(-6725 4550);
WIRE 16 -1 (-6900 4600)(-6900 4550);
WIRE 16 -1 (-6900 4650)(-6900 4600);
WIRE 16 -1 (-6900 4600)(-6725 4600);
WIRE 16 -1 (-6900 4650)(-6725 4650);
WIRE 16 -1 (-6900 4700)(-6900 4650);
WIRE 16 -1 (-6725 4700)(-6900 4700);
WIRE 16 -1 (-6900 4750)(-6900 4700);
WIRE 16 -1 (-6900 4750)(-6725 4750);
WIRE 16 -1 (-6900 4800)(-6900 4750);
WIRE 16 -1 (-6900 4800)(-6725 4800);
WIRE 16 -1 (-6900 4850)(-6900 4800);
WIRE 16 -1 (-6900 4900)(-6900 4850);
WIRE 16 -1 (-6900 4850)(-6725 4850);
WIRE 16 -1 (-6900 4900)(-6725 4900);
WIRE 16 -1 (-6900 4950)(-6900 4900);
WIRE 16 -1 (-6725 4950)(-6900 4950);
WIRE 16 -1 (-6900 5000)(-6900 4950);
WIRE 16 -1 (-6900 5000)(-6725 5000);
WIRE 16 -1 (-6900 5050)(-6900 5000);
WIRE 16 -1 (-6900 5050)(-6725 5050);
WIRE 16 -1 (-6900 5100)(-6900 5050);
WIRE 16 -1 (-6900 5150)(-6900 5100);
WIRE 16 -1 (-6900 5100)(-6725 5100);
WIRE 16 -1 (-6900 5150)(-6725 5150);
WIRE 16 -1 (-6900 5200)(-6900 5150);
WIRE 16 -1 (-6900 5200)(-6725 5200);
WIRE 16 -1 (-6900 5250)(-6900 5200);
WIRE 16 -1 (-6725 5250)(-6900 5250);
WIRE 16 -1 (-6900 5300)(-6900 5250);
WIRE 16 -1 (-6900 5300)(-6725 5300);
WIRE 16 -1 (-6900 5350)(-6900 5300);
WIRE 16 -1 (-6900 5400)(-6900 5350);
WIRE 16 -1 (-6900 5350)(-6725 5350);
WIRE 16 -1 (-6900 5400)(-6725 5400);
WIRE 16 -1 (-6900 5450)(-6900 5400);
WIRE 16 -1 (-6900 5450)(-6725 5450);
WIRE 16 -1 (-6900 5500)(-6900 5450);
WIRE 16 -1 (-6725 5500)(-6900 5500);
WIRE 16 -1 (-6900 5550)(-6900 5500);
WIRE 16 -1 (-6900 5550)(-6725 5550);
WIRE 16 -1 (-6900 5600)(-6900 5550);
WIRE 16 -1 (-6900 5650)(-6900 5600);
WIRE 16 -1 (-6900 5600)(-6725 5600);
WIRE 16 -1 (-6900 5650)(-6725 5650);
WIRE 16 -1 (-6900 5700)(-6900 5650);
WIRE 16 -1 (-6900 5700)(-6725 5700);
WIRE 16 -1 (-6900 5750)(-6900 5700);
WIRE 16 -1 (-6725 5750)(-6900 5750);
WIRE 16 -1 (-6900 5800)(-6900 5750);
WIRE 16 -1 (-6900 5800)(-6725 5800);
WIRE 16 -1 (-6900 5850)(-6900 5800);
WIRE 16 -1 (-6900 5900)(-6900 5850);
WIRE 16 -1 (-6900 5850)(-6725 5850);
WIRE 16 -1 (-6900 5900)(-6725 5900);
WIRE 16 -1 (-6900 5950)(-6900 5900);
WIRE 16 -1 (-6900 5950)(-6725 5950);
WIRE 16 -1 (-6900 6000)(-6900 5950);
WIRE 16 -1 (-6725 6000)(-6900 6000);
WIRE 16 -1 (-6900 6050)(-6900 6000);
WIRE 16 -1 (-6900 6050)(-6725 6050);
WIRE 16 -1 (-6900 6100)(-6900 6050);
WIRE 16 -1 (-6900 6175)(-6900 6100);
WIRE 16 -1 (-6900 6100)(-6725 6100);
WIRE 16 -1 (-5425 250)(-5275 250);
WIRE 16 -1 (-5275 300)(-5275 250);
WIRE 16 -1 (-5425 300)(-5275 300);
WIRE 16 -1 (-5275 350)(-5275 300);
WIRE 16 -1 (-5425 350)(-5275 350);
WIRE 16 -1 (-5275 400)(-5275 350);
WIRE 16 -1 (-5425 400)(-5275 400);
WIRE 16 -1 (-5275 450)(-5275 400);
WIRE 16 -1 (-5425 450)(-5275 450);
WIRE 16 -1 (-5275 450)(-5275 500);
WIRE 16 -1 (-5425 500)(-5275 500);
WIRE 16 -1 (-5275 550)(-5275 500);
WIRE 16 -1 (-5275 600)(-5275 550);
WIRE 16 -1 (-5425 550)(-5275 550);
WIRE 16 -1 (-5425 600)(-5275 600);
WIRE 16 -1 (-5275 600)(-5275 650);
WIRE 16 -1 (-5425 650)(-5275 650);
WIRE 16 -1 (-5275 700)(-5275 650);
WIRE 16 -1 (-5425 700)(-5275 700);
WIRE 16 -1 (-5275 750)(-5275 700);
WIRE 16 -1 (-5425 750)(-5275 750);
WIRE 16 -1 (-5275 750)(-5275 800);
WIRE 16 -1 (-5425 800)(-5275 800);
WIRE 16 -1 (-5275 850)(-5275 800);
WIRE 16 -1 (-5425 850)(-5275 850);
WIRE 16 -1 (-5275 900)(-5275 850);
WIRE 16 -1 (-5425 900)(-5275 900);
WIRE 16 -1 (-5275 950)(-5275 900);
WIRE 16 -1 (-5425 950)(-5275 950);
WIRE 16 -1 (-5275 1000)(-5275 950);
WIRE 16 -1 (-5425 1000)(-5275 1000);
WIRE 16 -1 (-5275 1000)(-5275 1050);
WIRE 16 -1 (-5275 1100)(-5275 1050);
WIRE 16 -1 (-5425 1050)(-5275 1050);
WIRE 16 -1 (-5425 1100)(-5275 1100);
WIRE 16 -1 (-5275 1150)(-5275 1100);
WIRE 16 -1 (-5425 1150)(-5275 1150);
WIRE 16 -1 (-5275 1200)(-5275 1150);
WIRE 16 -1 (-5425 1200)(-5275 1200);
WIRE 16 -1 (-5275 1250)(-5275 1200);
WIRE 16 -1 (-5425 1250)(-5275 1250);
WIRE 16 -1 (-5275 1250)(-5275 1300);
WIRE 16 -1 (-5425 1300)(-5275 1300);
WIRE 16 -1 (-5275 1350)(-5275 1300);
WIRE 16 -1 (-5425 1350)(-5275 1350);
WIRE 16 -1 (-5275 1400)(-5275 1350);
WIRE 16 -1 (-5425 1400)(-5275 1400);
WIRE 16 -1 (-5275 1450)(-5275 1400);
WIRE 16 -1 (-5425 1450)(-5275 1450);
WIRE 16 -1 (-5275 1500)(-5275 1450);
WIRE 16 -1 (-5425 1500)(-5275 1500);
WIRE 16 -1 (-5275 1500)(-5275 1550);
WIRE 16 -1 (-5275 1600)(-5275 1550);
WIRE 16 -1 (-5425 1550)(-5275 1550);
WIRE 16 -1 (-5425 1600)(-5275 1600);
WIRE 16 -1 (-5275 1650)(-5275 1600);
WIRE 16 -1 (-5425 1650)(-5275 1650);
WIRE 16 -1 (-5275 1650)(-5275 1700);
WIRE 16 -1 (-5425 1700)(-5275 1700);
WIRE 16 -1 (-5275 1750)(-5275 1700);
WIRE 16 -1 (-5425 1750)(-5275 1750);
WIRE 16 -1 (-5275 1800)(-5275 1750);
WIRE 16 -1 (-5425 1800)(-5275 1800);
WIRE 16 -1 (-5275 1800)(-5275 1850);
WIRE 16 -1 (-5425 1850)(-5275 1850);
WIRE 16 -1 (-5275 1900)(-5275 1850);
WIRE 16 -1 (-5425 1900)(-5275 1900);
WIRE 16 -1 (-5275 1950)(-5275 1900);
WIRE 16 -1 (-5425 1950)(-5275 1950);
WIRE 16 -1 (-5275 2000)(-5275 1950);
WIRE 16 -1 (-5425 2000)(-5275 2000);
WIRE 16 -1 (-5275 2050)(-5275 2000);
WIRE 16 -1 (-5275 2050)(-5275 2100);
WIRE 16 -1 (-5425 2050)(-5275 2050);
WIRE 16 -1 (-5425 2100)(-5275 2100);
WIRE 16 -1 (-5275 2150)(-5275 2100);
WIRE 16 -1 (-5425 2150)(-5275 2150);
WIRE 16 -1 (-5275 2200)(-5275 2150);
WIRE 16 -1 (-5425 2200)(-5275 2200);
WIRE 16 -1 (-5275 2250)(-5275 2200);
WIRE 16 -1 (-5425 2250)(-5275 2250);
WIRE 16 -1 (-5275 2300)(-5275 2250);
WIRE 16 -1 (-5425 2300)(-5275 2300);
WIRE 16 -1 (-5275 2300)(-5275 2350);
WIRE 16 -1 (-5425 2350)(-5275 2350);
WIRE 16 -1 (-5275 2400)(-5275 2350);
WIRE 16 -1 (-5425 2400)(-5275 2400);
WIRE 16 -1 (-5275 2450)(-5275 2400);
WIRE 16 -1 (-5425 2450)(-5275 2450);
WIRE 16 -1 (-5275 2500)(-5275 2450);
WIRE 16 -1 (-5425 2500)(-5275 2500);
WIRE 16 -1 (-5275 2550)(-5275 2500);
WIRE 16 -1 (-5425 2550)(-5275 2550);
WIRE 16 -1 (-5275 2550)(-5275 2600);
WIRE 16 -1 (-5275 2650)(-5275 2600);
WIRE 16 -1 (-5425 2600)(-5275 2600);
WIRE 16 -1 (-5425 2650)(-5275 2650);
WIRE 16 -1 (-5275 2700)(-5275 2650);
WIRE 16 -1 (-5425 2700)(-5275 2700);
WIRE 16 -1 (-5275 2700)(-5275 2750);
WIRE 16 -1 (-5425 2750)(-5275 2750);
WIRE 16 -1 (-5275 2800)(-5275 2750);
WIRE 16 -1 (-5425 2800)(-5275 2800);
WIRE 16 -1 (-5275 2850)(-5275 2800);
WIRE 16 -1 (-5425 2850)(-5275 2850);
WIRE 16 -1 (-5275 2850)(-5275 2900);
WIRE 16 -1 (-5425 2900)(-5275 2900);
WIRE 16 -1 (-5275 2950)(-5275 2900);
WIRE 16 -1 (-5425 2950)(-5275 2950);
WIRE 16 -1 (-5275 3000)(-5275 2950);
WIRE 16 -1 (-5425 3000)(-5275 3000);
WIRE 16 -1 (-5275 3050)(-5275 3000);
WIRE 16 -1 (-5425 3050)(-5275 3050);
WIRE 16 -1 (-5275 3100)(-5275 3050);
WIRE 16 -1 (-5275 3100)(-5275 3150);
WIRE 16 -1 (-5425 3100)(-5275 3100);
WIRE 16 -1 (-5425 3150)(-5275 3150);
WIRE 16 -1 (-5275 3200)(-5275 3150);
WIRE 16 -1 (-5425 3200)(-5275 3200);
WIRE 16 -1 (-5275 3250)(-5275 3200);
WIRE 16 -1 (-5425 3250)(-5275 3250);
WIRE 16 -1 (-5275 3300)(-5275 3250);
WIRE 16 -1 (-5425 3300)(-5275 3300);
WIRE 16 -1 (-5275 3350)(-5275 3300);
WIRE 16 -1 (-5425 3350)(-5275 3350);
WIRE 16 -1 (-5275 3350)(-5275 3400);
WIRE 16 -1 (-5425 3400)(-5275 3400);
WIRE 16 -1 (-5275 3450)(-5275 3400);
WIRE 16 -1 (-5425 3450)(-5275 3450);
WIRE 16 -1 (-5275 3500)(-5275 3450);
WIRE 16 -1 (-5425 3500)(-5275 3500);
WIRE 16 -1 (-5275 3550)(-5275 3500);
WIRE 16 -1 (-5425 3550)(-5275 3550);
WIRE 16 -1 (-5275 3600)(-5275 3550);
WIRE 16 -1 (-5275 3600)(-5275 3650);
WIRE 16 -1 (-5425 3600)(-5275 3600);
WIRE 16 -1 (-5425 3650)(-5275 3650);
WIRE 16 -1 (-5275 3700)(-5275 3650);
WIRE 16 -1 (-5425 3700)(-5275 3700);
WIRE 16 -1 (-5275 3750)(-5275 3700);
WIRE 16 -1 (-5425 3750)(-5275 3750);
WIRE 16 -1 (-5275 3750)(-5275 3800);
WIRE 16 -1 (-5425 3800)(-5275 3800);
WIRE 16 -1 (-5275 3850)(-5275 3800);
WIRE 16 -1 (-5425 3850)(-5275 3850);
WIRE 16 -1 (-5275 3900)(-5275 3850);
WIRE 16 -1 (-5425 3900)(-5275 3900);
WIRE 16 -1 (-5275 3900)(-5275 3950);
WIRE 16 -1 (-5425 3950)(-5275 3950);
WIRE 16 -1 (-5275 4000)(-5275 3950);
WIRE 16 -1 (-5425 4000)(-5275 4000);
WIRE 16 -1 (-5275 4050)(-5275 4000);
WIRE 16 -1 (-5425 4050)(-5275 4050);
WIRE 16 -1 (-5275 4100)(-5275 4050);
WIRE 16 -1 (-5275 4150)(-5275 4100);
WIRE 16 -1 (-5425 4100)(-5275 4100);
WIRE 16 -1 (-5425 4150)(-5275 4150);
WIRE 16 -1 (-5275 4150)(-5275 4200);
WIRE 16 -1 (-5425 4200)(-5275 4200);
WIRE 16 -1 (-5275 4250)(-5275 4200);
WIRE 16 -1 (-5425 4250)(-5275 4250);
WIRE 16 -1 (-5275 4300)(-5275 4250);
WIRE 16 -1 (-5425 4300)(-5275 4300);
WIRE 16 -1 (-5275 4350)(-5275 4300);
WIRE 16 -1 (-5425 4350)(-5275 4350);
WIRE 16 -1 (-5275 4400)(-5275 4350);
WIRE 16 -1 (-5425 4400)(-5275 4400);
WIRE 16 -1 (-5275 4400)(-5275 4450);
WIRE 16 -1 (-5425 4450)(-5275 4450);
WIRE 16 -1 (-5275 4500)(-5275 4450);
WIRE 16 -1 (-5425 4500)(-5275 4500);
WIRE 16 -1 (-5275 4550)(-5275 4500);
WIRE 16 -1 (-5425 4550)(-5275 4550);
WIRE 16 -1 (-5275 4600)(-5275 4550);
WIRE 16 -1 (-5425 4600)(-5275 4600);
WIRE 16 -1 (-5275 4650)(-5275 4600);
WIRE 16 -1 (-5275 4650)(-5275 4700);
WIRE 16 -1 (-5425 4650)(-5275 4650);
WIRE 16 -1 (-5425 4700)(-5275 4700);
WIRE 16 -1 (-5275 4750)(-5275 4700);
WIRE 16 -1 (-5425 4750)(-5275 4750);
WIRE 16 -1 (-5275 4800)(-5275 4750);
WIRE 16 -1 (-5425 4800)(-5275 4800);
WIRE 16 -1 (-5275 4800)(-5275 4850);
WIRE 16 -1 (-5425 4850)(-5275 4850);
WIRE 16 -1 (-5275 4900)(-5275 4850);
WIRE 16 -1 (-5425 4900)(-5275 4900);
WIRE 16 -1 (-5275 4950)(-5275 4900);
WIRE 16 -1 (-5425 4950)(-5275 4950);
WIRE 16 -1 (-5275 4950)(-5275 5000);
WIRE 16 -1 (-5425 5000)(-5275 5000);
WIRE 16 -1 (-5275 5050)(-5275 5000);
WIRE 16 -1 (-5425 5050)(-5275 5050);
WIRE 16 -1 (-5275 5100)(-5275 5050);
WIRE 16 -1 (-5425 5100)(-5275 5100);
WIRE 16 -1 (-5275 5150)(-5275 5100);
WIRE 16 -1 (-5275 5200)(-5275 5150);
WIRE 16 -1 (-5425 5150)(-5275 5150);
WIRE 16 -1 (-5425 5200)(-5275 5200);
WIRE 16 -1 (-5275 5200)(-5275 5250);
WIRE 16 -1 (-5425 5250)(-5275 5250);
WIRE 16 -1 (-5275 5300)(-5275 5250);
WIRE 16 -1 (-5425 5300)(-5275 5300);
WIRE 16 -1 (-5275 5350)(-5275 5300);
WIRE 16 -1 (-5425 5350)(-5275 5350);
WIRE 16 -1 (-5275 5400)(-5275 5350);
WIRE 16 -1 (-5425 5400)(-5275 5400);
WIRE 16 -1 (-5275 5450)(-5275 5400);
WIRE 16 -1 (-5425 5450)(-5275 5450);
WIRE 16 -1 (-5275 5450)(-5275 5500);
WIRE 16 -1 (-5425 5500)(-5275 5500);
WIRE 16 -1 (-5275 5550)(-5275 5500);
WIRE 16 -1 (-5425 5550)(-5275 5550);
WIRE 16 -1 (-5275 5600)(-5275 5550);
WIRE 16 -1 (-5425 5600)(-5275 5600);
WIRE 16 -1 (-5275 5650)(-5275 5600);
WIRE 16 -1 (-5275 5700)(-5275 5650);
WIRE 16 -1 (-5425 5650)(-5275 5650);
WIRE 16 -1 (-5425 5700)(-5275 5700);
WIRE 16 -1 (-5275 5700)(-5275 5750);
WIRE 16 -1 (-5425 5750)(-5275 5750);
WIRE 16 -1 (-5275 5800)(-5275 5750);
WIRE 16 -1 (-5425 5800)(-5275 5800);
WIRE 16 -1 (-5275 5850)(-5275 5800);
WIRE 16 -1 (-5425 5850)(-5275 5850);
WIRE 16 -1 (-5275 5850)(-5275 5900);
WIRE 16 -1 (-5425 5900)(-5275 5900);
WIRE 16 -1 (-5275 5950)(-5275 5900);
WIRE 16 -1 (-5425 5950)(-5275 5950);
WIRE 16 -1 (-5275 6000)(-5275 5950);
WIRE 16 -1 (-5425 6000)(-5275 6000);
WIRE 16 -1 (-5275 6000)(-5275 6050);
WIRE 16 -1 (-5425 6050)(-5275 6050);
WIRE 16 -1 (-5275 6100)(-5275 6050);
WIRE 16 -1 (-5425 6100)(-5275 6100);
WIRE 16 -1 (-5275 6150)(-5275 6100);
WIRE 16 -1 (-5275 6200)(-5275 6150);
WIRE 16 -1 (-5425 6150)(-5275 6150);
WIRE 16 -1 (-5425 6200)(-5275 6200);
WIRE 16 -1 (-5275 6250)(-5275 6200);
WIRE 16 -1 (-5425 6250)(-5275 6250);
WIRE 16 -1 (-5275 6250)(-5275 6300);
WIRE 16 -1 (-5425 6300)(-5275 6300);
WIRE 16 -1 (-5275 6350)(-5275 6300);
WIRE 16 -1 (-5275 6400)(-5275 6350);
WIRE 16 -1 (-5275 6350)(-5425 6350);
WIRE 16 -1 (-5275 6425)(-5275 6400);
WIRE 16 -1 (-5425 6400)(-5275 6400);
WIRE 16 -1 (-4975 3075)(-4850 3075);
WIRE 16 -1 (-4975 3125)(-4975 3075);
WIRE 16 -1 (-4975 3125)(-4850 3125);
WIRE 16 -1 (-4975 3175)(-4975 3125);
WIRE 16 -1 (-4975 3175)(-4850 3175);
WIRE 16 -1 (-4975 3225)(-4975 3175);
WIRE 16 -1 (-4975 3225)(-4850 3225);
WIRE 16 -1 (-4975 3275)(-4975 3225);
WIRE 16 -1 (-4975 3275)(-4850 3275);
WIRE 16 -1 (-4975 3325)(-4975 3275);
WIRE 16 -1 (-4975 3325)(-4850 3325);
WIRE 16 -1 (-4975 3375)(-4975 3325);
WIRE 16 -1 (-4975 3375)(-4850 3375);
WIRE 16 -1 (-4975 3425)(-4975 3375);
WIRE 16 -1 (-4975 3425)(-4850 3425);
WIRE 16 -1 (-4975 3475)(-4975 3425);
WIRE 16 -1 (-4975 3475)(-4850 3475);
WIRE 16 -1 (-4975 3525)(-4975 3475);
WIRE 16 -1 (-4975 3525)(-4850 3525);
WIRE 16 -1 (-4975 3575)(-4975 3525);
WIRE 16 -1 (-4975 3625)(-4975 3575);
WIRE 16 -1 (-4850 3575)(-4975 3575);
WIRE 16 -1 (-4975 3625)(-4850 3625);
WIRE 16 -1 (-4975 3675)(-4975 3625);
WIRE 16 -1 (-4975 3675)(-4850 3675);
WIRE 16 -1 (-4975 3725)(-4975 3675);
WIRE 16 -1 (-4975 3725)(-4850 3725);
WIRE 16 -1 (-4975 3775)(-4975 3725);
WIRE 16 -1 (-4975 3775)(-4850 3775);
WIRE 16 -1 (-4975 3825)(-4975 3775);
WIRE 16 -1 (-4975 3825)(-4850 3825);
WIRE 16 -1 (-4975 3875)(-4975 3825);
WIRE 16 -1 (-4975 3875)(-4850 3875);
WIRE 16 -1 (-4975 3925)(-4975 3875);
WIRE 16 -1 (-4975 3925)(-4850 3925);
WIRE 16 -1 (-4975 3975)(-4975 3925);
WIRE 16 -1 (-4975 3975)(-4850 3975);
WIRE 16 -1 (-4975 4025)(-4975 3975);
WIRE 16 -1 (-4975 4025)(-4850 4025);
WIRE 16 -1 (-4975 4075)(-4975 4025);
WIRE 16 -1 (-4975 4125)(-4975 4075);
WIRE 16 -1 (-4850 4075)(-4975 4075);
WIRE 16 -1 (-4975 4125)(-4850 4125);
WIRE 16 -1 (-4975 4175)(-4975 4125);
WIRE 16 -1 (-4975 4175)(-4850 4175);
WIRE 16 -1 (-4975 4225)(-4975 4175);
WIRE 16 -1 (-4975 4225)(-4850 4225);
WIRE 16 -1 (-4975 4275)(-4975 4225);
WIRE 16 -1 (-4975 4275)(-4850 4275);
WIRE 16 -1 (-4975 4325)(-4975 4275);
WIRE 16 -1 (-4975 4325)(-4850 4325);
WIRE 16 -1 (-4975 4375)(-4975 4325);
WIRE 16 -1 (-4975 4375)(-4850 4375);
WIRE 16 -1 (-4975 4425)(-4975 4375);
WIRE 16 -1 (-4975 4425)(-4850 4425);
WIRE 16 -1 (-4975 4475)(-4975 4425);
WIRE 16 -1 (-4975 4475)(-4850 4475);
WIRE 16 -1 (-4975 4525)(-4975 4475);
WIRE 16 -1 (-4975 4525)(-4850 4525);
WIRE 16 -1 (-4975 4575)(-4975 4525);
WIRE 16 -1 (-4975 4625)(-4975 4575);
WIRE 16 -1 (-4850 4575)(-4975 4575);
WIRE 16 -1 (-4975 4625)(-4850 4625);
WIRE 16 -1 (-4975 4675)(-4975 4625);
WIRE 16 -1 (-4975 4675)(-4850 4675);
WIRE 16 -1 (-4975 4725)(-4975 4675);
WIRE 16 -1 (-4975 4725)(-4850 4725);
WIRE 16 -1 (-4975 4775)(-4975 4725);
WIRE 16 -1 (-4975 4775)(-4850 4775);
WIRE 16 -1 (-4975 4825)(-4975 4775);
WIRE 16 -1 (-4975 4825)(-4850 4825);
WIRE 16 -1 (-4975 4875)(-4975 4825);
WIRE 16 -1 (-4975 4875)(-4850 4875);
WIRE 16 -1 (-4975 4925)(-4975 4875);
WIRE 16 -1 (-4975 4925)(-4850 4925);
WIRE 16 -1 (-4975 4975)(-4975 4925);
WIRE 16 -1 (-4975 4975)(-4850 4975);
WIRE 16 -1 (-4975 5025)(-4975 4975);
WIRE 16 -1 (-4975 5025)(-4850 5025);
WIRE 16 -1 (-4975 5075)(-4975 5025);
WIRE 16 -1 (-4975 5125)(-4975 5075);
WIRE 16 -1 (-4850 5075)(-4975 5075);
WIRE 16 -1 (-4975 5125)(-4850 5125);
WIRE 16 -1 (-4975 5175)(-4975 5125);
WIRE 16 -1 (-4975 5175)(-4850 5175);
WIRE 16 -1 (-4975 5225)(-4975 5175);
WIRE 16 -1 (-4975 5225)(-4850 5225);
WIRE 16 -1 (-4975 5275)(-4975 5225);
WIRE 16 -1 (-4975 5275)(-4850 5275);
WIRE 16 -1 (-4975 5325)(-4975 5275);
WIRE 16 -1 (-4975 5325)(-4850 5325);
WIRE 16 -1 (-4975 5375)(-4975 5325);
WIRE 16 -1 (-4975 5375)(-4850 5375);
WIRE 16 -1 (-4975 5425)(-4975 5375);
WIRE 16 -1 (-4975 5425)(-4850 5425);
WIRE 16 -1 (-4975 5475)(-4975 5425);
WIRE 16 -1 (-4975 5475)(-4850 5475);
WIRE 16 -1 (-4975 5525)(-4975 5475);
WIRE 16 -1 (-4975 5525)(-4850 5525);
WIRE 16 -1 (-4975 5575)(-4975 5525);
WIRE 16 -1 (-4975 5575)(-4850 5575);
WIRE 16 -1 (-4975 5625)(-4975 5575);
WIRE 16 -1 (-4975 5675)(-4975 5625);
WIRE 16 -1 (-4850 5625)(-4975 5625);
WIRE 16 -1 (-4975 5675)(-4850 5675);
WIRE 16 -1 (-4975 5725)(-4975 5675);
WIRE 16 -1 (-4975 5725)(-4850 5725);
WIRE 16 -1 (-4975 5775)(-4975 5725);
WIRE 16 -1 (-4975 5775)(-4850 5775);
WIRE 16 -1 (-4975 5825)(-4975 5775);
WIRE 16 -1 (-4975 5825)(-4850 5825);
WIRE 16 -1 (-4975 5875)(-4975 5825);
WIRE 16 -1 (-4975 5875)(-4850 5875);
WIRE 16 -1 (-4975 5925)(-4975 5875);
WIRE 16 -1 (-4975 5925)(-4850 5925);
WIRE 16 -1 (-4975 5975)(-4975 5925);
WIRE 16 -1 (-4975 5975)(-4850 5975);
WIRE 16 -1 (-4975 6025)(-4975 5975);
WIRE 16 -1 (-4975 6025)(-4850 6025);
WIRE 16 -1 (-4975 6100)(-4975 6025);
WIRE 16 -1 (-3475 875)(-3125 875);
WIRE 16 -1 (-3475 875)(-3475 925);
WIRE 16 -1 (-3475 1025)(-3475 925);
WIRE 16 -1 (-3125 925)(-3475 925);
WIRE 16 -1 (-3475 1175)(-3125 1175);
WIRE 16 -1 (-3475 1525)(-3475 1175);
WIRE 16 -1 (-3475 1575)(-3475 1525);
WIRE 16 -1 (-3125 1525)(-3475 1525);
WIRE 16 -1 (-3475 1575)(-3125 1575);
WIRE 16 -1 (-3475 1625)(-3475 1575);
WIRE 16 -1 (-3475 1625)(-3125 1625);
WIRE 16 -1 (-3475 1675)(-3475 1625);
WIRE 16 -1 (-3475 1675)(-3125 1675);
WIRE 16 -1 (-3475 1725)(-3475 1675);
WIRE 16 -1 (-3475 1725)(-3125 1725);
WIRE 16 -1 (-3475 1775)(-3475 1725);
WIRE 16 -1 (-3475 1775)(-3125 1775);
WIRE 16 -1 (-3475 1825)(-3475 1775);
WIRE 16 -1 (-3475 1825)(-3125 1825);
WIRE 16 -1 (-3475 1875)(-3475 1825);
WIRE 16 -1 (-3475 1875)(-3125 1875);
WIRE 16 -1 (-3475 1925)(-3475 1875);
WIRE 16 -1 (-3475 1925)(-3125 1925);
WIRE 16 -1 (-3475 1975)(-3475 1925);
WIRE 16 -1 (-3475 1975)(-3125 1975);
WIRE 16 -1 (-3475 2025)(-3475 1975);
WIRE 16 -1 (-3475 2075)(-3475 2025);
WIRE 16 -1 (-3125 2025)(-3475 2025);
WIRE 16 -1 (-3475 2075)(-3125 2075);
WIRE 16 -1 (-3475 2125)(-3475 2075);
WIRE 16 -1 (-3475 2125)(-3125 2125);
WIRE 16 -1 (-3475 2175)(-3475 2125);
WIRE 16 -1 (-3475 2175)(-3125 2175);
WIRE 16 -1 (-3475 2225)(-3475 2175);
WIRE 16 -1 (-3475 2225)(-3125 2225);
WIRE 16 -1 (-3475 2275)(-3475 2225);
WIRE 16 -1 (-3475 2275)(-3125 2275);
WIRE 16 -1 (-3475 2325)(-3475 2275);
WIRE 16 -1 (-3475 2325)(-3125 2325);
WIRE 16 -1 (-3475 2375)(-3475 2325);
WIRE 16 -1 (-3475 2375)(-3125 2375);
WIRE 16 -1 (-3475 2425)(-3475 2375);
WIRE 16 -1 (-3475 2425)(-3125 2425);
WIRE 16 -1 (-3475 2475)(-3475 2425);
WIRE 16 -1 (-3475 2475)(-3125 2475);
WIRE 16 -1 (-3475 2525)(-3475 2475);
WIRE 16 -1 (-3475 2625)(-3475 2525);
WIRE 16 -1 (-3475 2525)(-3125 2525);
WIRE 16 -1 (-3125 2625)(-3475 2625);
WIRE 16 -1 (-3475 2775)(-3475 2625);
WIRE 16 -1 (-3300 2725)(-3125 2725);
WIRE 16 -1 (-3300 2775)(-3300 2725);
WIRE 16 -1 (-3300 2825)(-3300 2775);
WIRE 16 -1 (-3125 2775)(-3300 2775);
WIRE 16 -1 (-3300 2825)(-3125 2825);
WIRE 16 -1 (-3300 2875)(-3300 2825);
WIRE 16 -1 (-3300 2875)(-3125 2875);
WIRE 16 -1 (-3300 2925)(-3300 2875);
WIRE 16 -1 (-3300 2925)(-3125 2925);
WIRE 16 -1 (-3300 2975)(-3300 2925);
WIRE 16 -1 (-3300 2975)(-3125 2975);
WIRE 16 -1 (-3300 3025)(-3300 2975);
WIRE 16 -1 (-3300 3075)(-3300 3025);
WIRE 16 -1 (-3125 3025)(-3300 3025);
WIRE 16 -1 (-3300 3075)(-3125 3075);
WIRE 16 -1 (-3300 3125)(-3300 3075);
WIRE 16 -1 (-3300 3125)(-3125 3125);
WIRE 16 -1 (-3300 3175)(-3300 3125);
WIRE 16 -1 (-3300 3175)(-3125 3175);
WIRE 16 -1 (-3300 3225)(-3300 3175);
WIRE 16 -1 (-3300 3225)(-3125 3225);
WIRE 16 -1 (-3300 3275)(-3300 3225);
WIRE 16 -1 (-3300 3275)(-3125 3275);
WIRE 16 -1 (-3300 3325)(-3300 3275);
WIRE 16 -1 (-3300 3375)(-3300 3325);
WIRE 16 -1 (-3125 3325)(-3300 3325);
WIRE 16 -1 (-3300 3375)(-3125 3375);
WIRE 16 -1 (-3300 3425)(-3300 3375);
WIRE 16 -1 (-3300 3425)(-3125 3425);
WIRE 16 -1 (-3300 3475)(-3300 3425);
WIRE 16 -1 (-3300 3475)(-3125 3475);
WIRE 16 -1 (-3300 3525)(-3300 3475);
WIRE 16 -1 (-3300 3525)(-3125 3525);
WIRE 16 -1 (-3300 3575)(-3300 3525);
WIRE 16 -1 (-3300 3625)(-3300 3575);
WIRE 16 -1 (-3125 3575)(-3300 3575);
WIRE 16 -1 (-3300 3625)(-3125 3625);
WIRE 16 -1 (-3300 3675)(-3300 3625);
WIRE 16 -1 (-3300 3675)(-3125 3675);
WIRE 16 -1 (-3300 3725)(-3300 3675);
WIRE 16 -1 (-3300 3725)(-3125 3725);
WIRE 16 -1 (-3300 3775)(-3300 3725);
WIRE 16 -1 (-3300 3775)(-3125 3775);
WIRE 16 -1 (-3300 3825)(-3300 3775);
WIRE 16 -1 (-3300 3875)(-3300 3825);
WIRE 16 -1 (-3125 3825)(-3300 3825);
WIRE 16 -1 (-3300 3875)(-3125 3875);
WIRE 16 -1 (-3300 3925)(-3300 3875);
WIRE 16 -1 (-3300 3925)(-3125 3925);
WIRE 16 -1 (-3300 3975)(-3300 3925);
WIRE 16 -1 (-3300 3975)(-3125 3975);
WIRE 16 -1 (-3300 4025)(-3300 3975);
WIRE 16 -1 (-3300 4025)(-3125 4025);
WIRE 16 -1 (-3300 4075)(-3300 4025);
WIRE 16 -1 (-3300 4125)(-3300 4075);
WIRE 16 -1 (-3125 4075)(-3300 4075);
WIRE 16 -1 (-3300 4125)(-3125 4125);
WIRE 16 -1 (-3300 4175)(-3300 4125);
WIRE 16 -1 (-3300 4175)(-3125 4175);
WIRE 16 -1 (-3300 4225)(-3300 4175);
WIRE 16 -1 (-3300 4225)(-3125 4225);
WIRE 16 -1 (-3300 4275)(-3300 4225);
WIRE 16 -1 (-3300 4275)(-3125 4275);
WIRE 16 -1 (-3300 4325)(-3300 4275);
WIRE 16 -1 (-3300 4375)(-3300 4325);
WIRE 16 -1 (-3125 4325)(-3300 4325);
WIRE 16 -1 (-3300 4375)(-3125 4375);
WIRE 16 -1 (-3300 4425)(-3300 4375);
WIRE 16 -1 (-3300 4425)(-3125 4425);
WIRE 16 -1 (-3300 4475)(-3300 4425);
WIRE 16 -1 (-3300 4475)(-3125 4475);
WIRE 16 -1 (-3300 4525)(-3300 4475);
WIRE 16 -1 (-3300 4525)(-3125 4525);
WIRE 16 -1 (-3300 4575)(-3300 4525);
WIRE 16 -1 (-3300 4625)(-3300 4575);
WIRE 16 -1 (-3125 4575)(-3300 4575);
WIRE 16 -1 (-3300 4625)(-3125 4625);
WIRE 16 -1 (-3300 4675)(-3300 4625);
WIRE 16 -1 (-3300 4675)(-3125 4675);
WIRE 16 -1 (-3300 4725)(-3300 4675);
WIRE 16 -1 (-3300 4725)(-3125 4725);
WIRE 16 -1 (-3300 4775)(-3300 4725);
WIRE 16 -1 (-3300 4775)(-3125 4775);
WIRE 16 -1 (-3300 4825)(-3300 4775);
WIRE 16 -1 (-3300 4875)(-3300 4825);
WIRE 16 -1 (-3125 4825)(-3300 4825);
WIRE 16 -1 (-3300 4875)(-3125 4875);
WIRE 16 -1 (-3300 4925)(-3300 4875);
WIRE 16 -1 (-3300 4925)(-3125 4925);
WIRE 16 -1 (-3300 4975)(-3300 4925);
WIRE 16 -1 (-3300 4975)(-3125 4975);
WIRE 16 -1 (-3300 5025)(-3300 4975);
WIRE 16 -1 (-3300 5025)(-3125 5025);
WIRE 16 -1 (-3300 5075)(-3300 5025);
WIRE 16 -1 (-3300 5125)(-3300 5075);
WIRE 16 -1 (-3125 5075)(-3300 5075);
WIRE 16 -1 (-3300 5125)(-3125 5125);
WIRE 16 -1 (-3300 5175)(-3300 5125);
WIRE 16 -1 (-3300 5175)(-3125 5175);
WIRE 16 -1 (-3300 5225)(-3300 5175);
WIRE 16 -1 (-3300 5225)(-3125 5225);
WIRE 16 -1 (-3300 5275)(-3300 5225);
WIRE 16 -1 (-3300 5275)(-3125 5275);
WIRE 16 -1 (-3300 5325)(-3300 5275);
WIRE 16 -1 (-3300 5325)(-3125 5325);
WIRE 16 -1 (-3300 5375)(-3300 5325);
WIRE 16 -1 (-3300 5425)(-3300 5375);
WIRE 16 -1 (-3125 5375)(-3300 5375);
WIRE 16 -1 (-3300 5425)(-3125 5425);
WIRE 16 -1 (-3300 5475)(-3300 5425);
WIRE 16 -1 (-3300 5475)(-3125 5475);
WIRE 16 -1 (-3300 5525)(-3300 5475);
WIRE 16 -1 (-3300 5525)(-3125 5525);
WIRE 16 -1 (-3300 5575)(-3300 5525);
WIRE 16 -1 (-3300 5575)(-3125 5575);
WIRE 16 -1 (-3300 5625)(-3300 5575);
WIRE 16 -1 (-3300 5675)(-3300 5625);
WIRE 16 -1 (-3125 5625)(-3300 5625);
WIRE 16 -1 (-3300 5675)(-3125 5675);
WIRE 16 -1 (-3300 5725)(-3300 5675);
WIRE 16 -1 (-3300 5725)(-3125 5725);
WIRE 16 -1 (-3300 5775)(-3300 5725);
WIRE 16 -1 (-3300 5775)(-3125 5775);
WIRE 16 -1 (-3300 5825)(-3300 5775);
WIRE 16 -1 (-3300 5825)(-3125 5825);
WIRE 16 -1 (-3300 5875)(-3300 5825);
WIRE 16 -1 (-3300 5925)(-3300 5875);
WIRE 16 -1 (-3125 5875)(-3300 5875);
WIRE 16 -1 (-3300 5925)(-3125 5925);
WIRE 16 -1 (-3300 5975)(-3300 5925);
WIRE 16 -1 (-3300 5975)(-3125 5975);
WIRE 16 -1 (-3300 6025)(-3300 5975);
WIRE 16 -1 (-3300 6025)(-3125 6025);
WIRE 16 -1 (-3300 6075)(-3300 6025);
WIRE 16 -1 (-3300 6075)(-3125 6075);
WIRE 16 -1 (-3300 6125)(-3300 6075);
WIRE 16 -1 (-3300 6175)(-3300 6125);
WIRE 16 -1 (-3125 6125)(-3300 6125);
WIRE 16 -1 (-3300 6175)(-3125 6175);
WIRE 16 -1 (-3300 6225)(-3300 6175);
WIRE 16 -1 (-3300 6225)(-3125 6225);
WIRE 16 -1 (-3300 6275)(-3300 6225);
WIRE 16 -1 (-3300 6275)(-3125 6275);
WIRE 16 -1 (-3300 6325)(-3300 6275);
WIRE 16 -1 (-3300 6325)(-3125 6325);
WIRE 16 -1 (-3300 6375)(-3300 6325);
WIRE 16 -1 (-3300 6425)(-3300 6375);
WIRE 16 -1 (-3125 6375)(-3300 6375);
WIRE 16 -1 (-3300 6425)(-3125 6425);
WIRE 16 -1 (-3300 6475)(-3300 6425);
WIRE 16 -1 (-3300 6475)(-3125 6475);
WIRE 16 -1 (-3300 6525)(-3300 6475);
WIRE 16 -1 (-3300 6525)(-3125 6525);
WIRE 16 -1 (-3300 6550)(-3300 6525);
WIRE 16 -1 (-3650 3475)(-3500 3475);
WIRE 16 -1 (-3500 3525)(-3500 3475);
WIRE 16 -1 (-3650 3525)(-3500 3525);
WIRE 16 -1 (-3500 3575)(-3500 3525);
WIRE 16 -1 (-3650 3575)(-3500 3575);
WIRE 16 -1 (-3500 3625)(-3500 3575);
WIRE 16 -1 (-3650 3625)(-3500 3625);
WIRE 16 -1 (-3500 3675)(-3500 3625);
WIRE 16 -1 (-3650 3675)(-3500 3675);
WIRE 16 -1 (-3500 3725)(-3500 3675);
WIRE 16 -1 (-3650 3725)(-3500 3725);
WIRE 16 -1 (-3500 3775)(-3500 3725);
WIRE 16 -1 (-3650 3775)(-3500 3775);
WIRE 16 -1 (-3500 3825)(-3500 3775);
WIRE 16 -1 (-3650 3825)(-3500 3825);
WIRE 16 -1 (-3500 3875)(-3500 3825);
WIRE 16 -1 (-3650 3875)(-3500 3875);
WIRE 16 -1 (-3500 3925)(-3500 3875);
WIRE 16 -1 (-3650 3925)(-3500 3925);
WIRE 16 -1 (-3500 3975)(-3500 3925);
WIRE 16 -1 (-3650 3975)(-3500 3975);
WIRE 16 -1 (-3500 4025)(-3500 3975);
WIRE 16 -1 (-3650 4025)(-3500 4025);
WIRE 16 -1 (-3500 4075)(-3500 4025);
WIRE 16 -1 (-3650 4075)(-3500 4075);
WIRE 16 -1 (-3500 4125)(-3500 4075);
WIRE 16 -1 (-3500 4175)(-3500 4125);
WIRE 16 -1 (-3650 4125)(-3500 4125);
WIRE 16 -1 (-3650 4175)(-3500 4175);
WIRE 16 -1 (-3500 4225)(-3500 4175);
WIRE 16 -1 (-3650 4225)(-3500 4225);
WIRE 16 -1 (-3500 4275)(-3500 4225);
WIRE 16 -1 (-3650 4275)(-3500 4275);
WIRE 16 -1 (-3500 4325)(-3500 4275);
WIRE 16 -1 (-3650 4325)(-3500 4325);
WIRE 16 -1 (-3500 4375)(-3500 4325);
WIRE 16 -1 (-3650 4375)(-3500 4375);
WIRE 16 -1 (-3500 4425)(-3500 4375);
WIRE 16 -1 (-3650 4425)(-3500 4425);
WIRE 16 -1 (-3500 4475)(-3500 4425);
WIRE 16 -1 (-3650 4475)(-3500 4475);
WIRE 16 -1 (-3500 4525)(-3500 4475);
WIRE 16 -1 (-3650 4525)(-3500 4525);
WIRE 16 -1 (-3500 4575)(-3500 4525);
WIRE 16 -1 (-3650 4575)(-3500 4575);
WIRE 16 -1 (-3500 4625)(-3500 4575);
WIRE 16 -1 (-3650 4625)(-3500 4625);
WIRE 16 -1 (-3500 4675)(-3500 4625);
WIRE 16 -1 (-3650 4675)(-3500 4675);
WIRE 16 -1 (-3500 4725)(-3500 4675);
WIRE 16 -1 (-3650 4725)(-3500 4725);
WIRE 16 -1 (-3500 4775)(-3500 4725);
WIRE 16 -1 (-3650 4775)(-3500 4775);
WIRE 16 -1 (-3500 4825)(-3500 4775);
WIRE 16 -1 (-3650 4825)(-3500 4825);
WIRE 16 -1 (-3500 4875)(-3500 4825);
WIRE 16 -1 (-3650 4875)(-3500 4875);
WIRE 16 -1 (-3500 4925)(-3500 4875);
WIRE 16 -1 (-3650 4925)(-3500 4925);
WIRE 16 -1 (-3500 4975)(-3500 4925);
WIRE 16 -1 (-3650 4975)(-3500 4975);
WIRE 16 -1 (-3500 5025)(-3500 4975);
WIRE 16 -1 (-3650 5025)(-3500 5025);
WIRE 16 -1 (-3500 5075)(-3500 5025);
WIRE 16 -1 (-3650 5075)(-3500 5075);
WIRE 16 -1 (-3500 5125)(-3500 5075);
WIRE 16 -1 (-3500 5175)(-3500 5125);
WIRE 16 -1 (-3650 5125)(-3500 5125);
WIRE 16 -1 (-3650 5175)(-3500 5175);
WIRE 16 -1 (-3500 5225)(-3500 5175);
WIRE 16 -1 (-3650 5225)(-3500 5225);
WIRE 16 -1 (-3500 5275)(-3500 5225);
WIRE 16 -1 (-3650 5275)(-3500 5275);
WIRE 16 -1 (-3500 5325)(-3500 5275);
WIRE 16 -1 (-3650 5325)(-3500 5325);
WIRE 16 -1 (-3500 5375)(-3500 5325);
WIRE 16 -1 (-3650 5375)(-3500 5375);
WIRE 16 -1 (-3500 5425)(-3500 5375);
WIRE 16 -1 (-3650 5425)(-3500 5425);
WIRE 16 -1 (-3500 5475)(-3500 5425);
WIRE 16 -1 (-3650 5475)(-3500 5475);
WIRE 16 -1 (-3500 5525)(-3500 5475);
WIRE 16 -1 (-3650 5525)(-3500 5525);
WIRE 16 -1 (-3500 5575)(-3500 5525);
WIRE 16 -1 (-3650 5575)(-3500 5575);
WIRE 16 -1 (-3500 5625)(-3500 5575);
WIRE 16 -1 (-3650 5625)(-3500 5625);
WIRE 16 -1 (-3500 5675)(-3500 5625);
WIRE 16 -1 (-3650 5675)(-3500 5675);
WIRE 16 -1 (-3500 5725)(-3500 5675);
WIRE 16 -1 (-3650 5725)(-3500 5725);
WIRE 16 -1 (-3500 5775)(-3500 5725);
WIRE 16 -1 (-3650 5775)(-3500 5775);
WIRE 16 -1 (-3500 5825)(-3500 5775);
WIRE 16 -1 (-3650 5825)(-3500 5825);
WIRE 16 -1 (-3500 5875)(-3500 5825);
WIRE 16 -1 (-3650 5875)(-3500 5875);
WIRE 16 -1 (-3500 5925)(-3500 5875);
WIRE 16 -1 (-3650 5925)(-3500 5925);
WIRE 16 -1 (-3500 5975)(-3500 5925);
WIRE 16 -1 (-3500 6025)(-3500 5975);
WIRE 16 -1 (-3650 5975)(-3500 5975);
WIRE 16 -1 (-3500 6025)(-3500 6100);
WIRE 16 -1 (-3650 6025)(-3500 6025);
WIRE 16 -1 (-1825 825)(-1675 825);
WIRE 16 -1 (-1675 875)(-1675 825);
WIRE 16 -1 (-1825 875)(-1675 875);
WIRE 16 -1 (-1675 925)(-1675 875);
WIRE 16 -1 (-1825 925)(-1675 925);
WIRE 16 -1 (-1675 975)(-1675 925);
WIRE 16 -1 (-1825 975)(-1675 975);
WIRE 16 -1 (-1675 1025)(-1675 975);
WIRE 16 -1 (-1675 1075)(-1675 1025);
WIRE 16 -1 (-1825 1025)(-1675 1025);
WIRE 16 -1 (-1825 1075)(-1675 1075);
WIRE 16 -1 (-1675 1125)(-1675 1075);
WIRE 16 -1 (-1825 1125)(-1675 1125);
WIRE 16 -1 (-1675 1175)(-1675 1125);
WIRE 16 -1 (-1825 1175)(-1675 1175);
WIRE 16 -1 (-1675 1225)(-1675 1175);
WIRE 16 -1 (-1825 1225)(-1675 1225);
WIRE 16 -1 (-1675 1275)(-1675 1225);
WIRE 16 -1 (-1825 1275)(-1675 1275);
WIRE 16 -1 (-1675 1325)(-1675 1275);
WIRE 16 -1 (-1825 1325)(-1675 1325);
WIRE 16 -1 (-1675 1375)(-1675 1325);
WIRE 16 -1 (-1825 1375)(-1675 1375);
WIRE 16 -1 (-1675 1425)(-1675 1375);
WIRE 16 -1 (-1825 1425)(-1675 1425);
WIRE 16 -1 (-1675 1475)(-1675 1425);
WIRE 16 -1 (-1825 1475)(-1675 1475);
WIRE 16 -1 (-1675 1525)(-1675 1475);
WIRE 16 -1 (-1825 1525)(-1675 1525);
WIRE 16 -1 (-1675 1575)(-1675 1525);
WIRE 16 -1 (-1675 1625)(-1675 1575);
WIRE 16 -1 (-1825 1575)(-1675 1575);
WIRE 16 -1 (-1825 1625)(-1675 1625);
WIRE 16 -1 (-1675 1675)(-1675 1625);
WIRE 16 -1 (-1825 1675)(-1675 1675);
WIRE 16 -1 (-1675 1725)(-1675 1675);
WIRE 16 -1 (-1825 1725)(-1675 1725);
WIRE 16 -1 (-1675 1775)(-1675 1725);
WIRE 16 -1 (-1825 1775)(-1675 1775);
WIRE 16 -1 (-1675 1825)(-1675 1775);
WIRE 16 -1 (-1825 1825)(-1675 1825);
WIRE 16 -1 (-1675 1875)(-1675 1825);
WIRE 16 -1 (-1825 1875)(-1675 1875);
WIRE 16 -1 (-1675 1925)(-1675 1875);
WIRE 16 -1 (-1825 1925)(-1675 1925);
WIRE 16 -1 (-1675 1975)(-1675 1925);
WIRE 16 -1 (-1825 1975)(-1675 1975);
WIRE 16 -1 (-1675 2025)(-1675 1975);
WIRE 16 -1 (-1825 2025)(-1675 2025);
WIRE 16 -1 (-1675 2075)(-1675 2025);
WIRE 16 -1 (-1675 2125)(-1675 2075);
WIRE 16 -1 (-1825 2075)(-1675 2075);
WIRE 16 -1 (-1825 2125)(-1675 2125);
WIRE 16 -1 (-1675 2175)(-1675 2125);
WIRE 16 -1 (-1825 2175)(-1675 2175);
WIRE 16 -1 (-1675 2225)(-1675 2175);
WIRE 16 -1 (-1825 2225)(-1675 2225);
WIRE 16 -1 (-1675 2275)(-1675 2225);
WIRE 16 -1 (-1825 2275)(-1675 2275);
WIRE 16 -1 (-1675 2325)(-1675 2275);
WIRE 16 -1 (-1825 2325)(-1675 2325);
WIRE 16 -1 (-1675 2375)(-1675 2325);
WIRE 16 -1 (-1825 2375)(-1675 2375);
WIRE 16 -1 (-1675 2425)(-1675 2375);
WIRE 16 -1 (-1825 2425)(-1675 2425);
WIRE 16 -1 (-1675 2475)(-1675 2425);
WIRE 16 -1 (-1825 2475)(-1675 2475);
WIRE 16 -1 (-1675 2525)(-1675 2475);
WIRE 16 -1 (-1825 2525)(-1675 2525);
WIRE 16 -1 (-1675 2575)(-1675 2525);
WIRE 16 -1 (-1675 2625)(-1675 2575);
WIRE 16 -1 (-1825 2575)(-1675 2575);
WIRE 16 -1 (-1825 2625)(-1675 2625);
WIRE 16 -1 (-1675 2675)(-1675 2625);
WIRE 16 -1 (-1825 2675)(-1675 2675);
WIRE 16 -1 (-1675 2725)(-1675 2675);
WIRE 16 -1 (-1825 2725)(-1675 2725);
WIRE 16 -1 (-1675 2775)(-1675 2725);
WIRE 16 -1 (-1825 2775)(-1675 2775);
WIRE 16 -1 (-1675 2825)(-1675 2775);
WIRE 16 -1 (-1825 2825)(-1675 2825);
WIRE 16 -1 (-1675 2875)(-1675 2825);
WIRE 16 -1 (-1825 2875)(-1675 2875);
WIRE 16 -1 (-1675 2925)(-1675 2875);
WIRE 16 -1 (-1825 2925)(-1675 2925);
WIRE 16 -1 (-1675 2975)(-1675 2925);
WIRE 16 -1 (-1825 2975)(-1675 2975);
WIRE 16 -1 (-1675 3025)(-1675 2975);
WIRE 16 -1 (-1825 3025)(-1675 3025);
WIRE 16 -1 (-1675 3075)(-1675 3025);
WIRE 16 -1 (-1675 3125)(-1675 3075);
WIRE 16 -1 (-1825 3075)(-1675 3075);
WIRE 16 -1 (-1825 3125)(-1675 3125);
WIRE 16 -1 (-1675 3175)(-1675 3125);
WIRE 16 -1 (-1825 3175)(-1675 3175);
WIRE 16 -1 (-1675 3225)(-1675 3175);
WIRE 16 -1 (-1825 3225)(-1675 3225);
WIRE 16 -1 (-1675 3275)(-1675 3225);
WIRE 16 -1 (-1825 3275)(-1675 3275);
WIRE 16 -1 (-1675 3325)(-1675 3275);
WIRE 16 -1 (-1825 3325)(-1675 3325);
WIRE 16 -1 (-1675 3375)(-1675 3325);
WIRE 16 -1 (-1825 3375)(-1675 3375);
WIRE 16 -1 (-1675 3425)(-1675 3375);
WIRE 16 -1 (-1825 3425)(-1675 3425);
WIRE 16 -1 (-1675 3475)(-1675 3425);
WIRE 16 -1 (-1825 3475)(-1675 3475);
WIRE 16 -1 (-1675 3525)(-1675 3475);
WIRE 16 -1 (-1825 3525)(-1675 3525);
WIRE 16 -1 (-1675 3575)(-1675 3525);
WIRE 16 -1 (-1825 3575)(-1675 3575);
WIRE 16 -1 (-1675 3625)(-1675 3575);
WIRE 16 -1 (-1675 3675)(-1675 3625);
WIRE 16 -1 (-1825 3625)(-1675 3625);
WIRE 16 -1 (-1825 3675)(-1675 3675);
WIRE 16 -1 (-1675 3725)(-1675 3675);
WIRE 16 -1 (-1825 3725)(-1675 3725);
WIRE 16 -1 (-1675 3775)(-1675 3725);
WIRE 16 -1 (-1825 3775)(-1675 3775);
WIRE 16 -1 (-1675 3825)(-1675 3775);
WIRE 16 -1 (-1825 3825)(-1675 3825);
WIRE 16 -1 (-1675 3875)(-1675 3825);
WIRE 16 -1 (-1825 3875)(-1675 3875);
WIRE 16 -1 (-1675 3925)(-1675 3875);
WIRE 16 -1 (-1825 3925)(-1675 3925);
WIRE 16 -1 (-1675 3975)(-1675 3925);
WIRE 16 -1 (-1825 3975)(-1675 3975);
WIRE 16 -1 (-1675 4025)(-1675 3975);
WIRE 16 -1 (-1825 4025)(-1675 4025);
WIRE 16 -1 (-1675 4075)(-1675 4025);
WIRE 16 -1 (-1825 4075)(-1675 4075);
WIRE 16 -1 (-1675 4125)(-1675 4075);
WIRE 16 -1 (-1675 4175)(-1675 4125);
WIRE 16 -1 (-1825 4125)(-1675 4125);
WIRE 16 -1 (-1825 4175)(-1675 4175);
WIRE 16 -1 (-1675 4225)(-1675 4175);
WIRE 16 -1 (-1825 4225)(-1675 4225);
WIRE 16 -1 (-1675 4275)(-1675 4225);
WIRE 16 -1 (-1825 4275)(-1675 4275);
WIRE 16 -1 (-1675 4325)(-1675 4275);
WIRE 16 -1 (-1825 4325)(-1675 4325);
WIRE 16 -1 (-1675 4375)(-1675 4325);
WIRE 16 -1 (-1825 4375)(-1675 4375);
WIRE 16 -1 (-1675 4425)(-1675 4375);
WIRE 16 -1 (-1825 4425)(-1675 4425);
WIRE 16 -1 (-1675 4475)(-1675 4425);
WIRE 16 -1 (-1825 4475)(-1675 4475);
WIRE 16 -1 (-1675 4525)(-1675 4475);
WIRE 16 -1 (-1825 4525)(-1675 4525);
WIRE 16 -1 (-1675 4575)(-1675 4525);
WIRE 16 -1 (-1825 4575)(-1675 4575);
WIRE 16 -1 (-1675 4625)(-1675 4575);
WIRE 16 -1 (-1675 4675)(-1675 4625);
WIRE 16 -1 (-1825 4625)(-1675 4625);
WIRE 16 -1 (-1825 4675)(-1675 4675);
WIRE 16 -1 (-1675 4725)(-1675 4675);
WIRE 16 -1 (-1825 4725)(-1675 4725);
WIRE 16 -1 (-1675 4775)(-1675 4725);
WIRE 16 -1 (-1825 4775)(-1675 4775);
WIRE 16 -1 (-1675 4825)(-1675 4775);
WIRE 16 -1 (-1825 4825)(-1675 4825);
WIRE 16 -1 (-1675 4875)(-1675 4825);
WIRE 16 -1 (-1825 4875)(-1675 4875);
WIRE 16 -1 (-1675 4925)(-1675 4875);
WIRE 16 -1 (-1825 4925)(-1675 4925);
WIRE 16 -1 (-1675 4975)(-1675 4925);
WIRE 16 -1 (-1825 4975)(-1675 4975);
WIRE 16 -1 (-1675 5025)(-1675 4975);
WIRE 16 -1 (-1825 5025)(-1675 5025);
WIRE 16 -1 (-1675 5075)(-1675 5025);
WIRE 16 -1 (-1825 5075)(-1675 5075);
WIRE 16 -1 (-1675 5125)(-1675 5075);
WIRE 16 -1 (-1675 5175)(-1675 5125);
WIRE 16 -1 (-1825 5125)(-1675 5125);
WIRE 16 -1 (-1825 5175)(-1675 5175);
WIRE 16 -1 (-1675 5225)(-1675 5175);
WIRE 16 -1 (-1825 5225)(-1675 5225);
WIRE 16 -1 (-1675 5275)(-1675 5225);
WIRE 16 -1 (-1825 5275)(-1675 5275);
WIRE 16 -1 (-1675 5325)(-1675 5275);
WIRE 16 -1 (-1825 5325)(-1675 5325);
WIRE 16 -1 (-1675 5375)(-1675 5325);
WIRE 16 -1 (-1825 5375)(-1675 5375);
WIRE 16 -1 (-1675 5425)(-1675 5375);
WIRE 16 -1 (-1825 5425)(-1675 5425);
WIRE 16 -1 (-1675 5475)(-1675 5425);
WIRE 16 -1 (-1825 5475)(-1675 5475);
WIRE 16 -1 (-1675 5525)(-1675 5475);
WIRE 16 -1 (-1825 5525)(-1675 5525);
WIRE 16 -1 (-1675 5575)(-1675 5525);
WIRE 16 -1 (-1825 5575)(-1675 5575);
WIRE 16 -1 (-1675 5625)(-1675 5575);
WIRE 16 -1 (-1825 5625)(-1675 5625);
WIRE 16 -1 (-1675 5675)(-1675 5625);
WIRE 16 -1 (-1675 5725)(-1675 5675);
WIRE 16 -1 (-1825 5675)(-1675 5675);
WIRE 16 -1 (-1675 5775)(-1675 5725);
WIRE 16 -1 (-1675 5725)(-1825 5725);
WIRE 16 -1 (-1825 5775)(-1675 5775);
WIRE 16 -1 (-1675 5825)(-1675 5775);
WIRE 16 -1 (-1825 5825)(-1675 5825);
WIRE 16 -1 (-1675 5875)(-1675 5825);
WIRE 16 -1 (-1825 5875)(-1675 5875);
WIRE 16 -1 (-1675 5925)(-1675 5875);
WIRE 16 -1 (-1825 5925)(-1675 5925);
WIRE 16 -1 (-1675 5975)(-1675 5925);
WIRE 16 -1 (-1825 5975)(-1675 5975);
WIRE 16 -1 (-1675 6025)(-1675 5975);
WIRE 16 -1 (-1825 6025)(-1675 6025);
WIRE 16 -1 (-1675 6075)(-1675 6025);
WIRE 16 -1 (-1825 6075)(-1675 6075);
WIRE 16 -1 (-1675 6125)(-1675 6075);
WIRE 16 -1 (-1825 6125)(-1675 6125);
WIRE 16 -1 (-1675 6175)(-1675 6125);
WIRE 16 -1 (-1675 6225)(-1675 6175);
WIRE 16 -1 (-1825 6175)(-1675 6175);
WIRE 16 -1 (-1825 6225)(-1675 6225);
WIRE 16 -1 (-1675 6275)(-1675 6225);
WIRE 16 -1 (-1825 6275)(-1675 6275);
WIRE 16 -1 (-1675 6325)(-1675 6275);
WIRE 16 -1 (-1825 6325)(-1675 6325);
WIRE 16 -1 (-1675 6375)(-1675 6325);
WIRE 16 -1 (-1825 6375)(-1675 6375);
WIRE 16 -1 (-1675 6425)(-1675 6375);
WIRE 16 -1 (-1825 6425)(-1675 6425);
WIRE 16 -1 (-1675 6475)(-1675 6425);
WIRE 16 -1 (-1825 6475)(-1675 6475);
WIRE 16 -1 (-1675 6525)(-1675 6475);
WIRE 16 -1 (-1675 6575)(-1675 6525);
WIRE 16 -1 (-1825 6525)(-1675 6525);
DOT 1 (-5275 1150);
DOT 1 (-7250 4875);
DOT 1 (-7250 4825);
DOT 1 (-6900 4200);
DOT 1 (-1675 6525);
DOT 1 (-5275 6400);
DOT 1 (-4975 3175);
DOT 1 (-4975 3125);
DOT 1 (-4975 3325);
DOT 1 (-4975 3275);
DOT 1 (-4975 3225);
DOT 1 (-4975 3425);
DOT 1 (-4975 3375);
DOT 1 (-4975 3475);
DOT 1 (-4975 3525);
DOT 1 (-4975 3575);
DOT 1 (-4975 3675);
DOT 1 (-4975 3625);
DOT 1 (-4975 3725);
DOT 1 (-4975 3825);
DOT 1 (-4975 3775);
DOT 1 (-4975 3925);
DOT 1 (-4975 3875);
DOT 1 (-4975 3975);
DOT 1 (-4975 4025);
DOT 1 (-4975 4075);
DOT 1 (-4975 4175);
DOT 1 (-4975 4125);
DOT 1 (-4975 4225);
DOT 1 (-4975 4325);
DOT 1 (-4975 4275);
DOT 1 (-4975 4475);
DOT 1 (-4975 4425);
DOT 1 (-4975 4375);
DOT 1 (-4975 4525);
DOT 1 (-4975 4575);
DOT 1 (-4975 4725);
DOT 1 (-4975 4675);
DOT 1 (-4975 4625);
DOT 1 (-4975 4825);
DOT 1 (-4975 4775);
DOT 1 (-4975 4875);
DOT 1 (-4975 4925);
DOT 1 (-4975 4975);
DOT 1 (-4975 5025);
DOT 1 (-4975 5075);
DOT 1 (-4975 5125);
DOT 1 (-4975 5225);
DOT 1 (-4975 5175);
DOT 1 (-4975 5375);
DOT 1 (-4975 5325);
DOT 1 (-4975 5275);
DOT 1 (-4975 5475);
DOT 1 (-4975 5425);
DOT 1 (-4975 5525);
DOT 1 (-4975 5575);
DOT 1 (-4975 5625);
DOT 1 (-4975 5725);
DOT 1 (-4975 5675);
DOT 1 (-4975 5875);
DOT 1 (-4975 5825);
DOT 1 (-4975 5775);
DOT 1 (-4975 5925);
DOT 1 (-4975 5975);
DOT 1 (-4975 6025);
DOT 1 (-3500 3575);
DOT 1 (-3500 3525);
DOT 1 (-3500 3675);
DOT 1 (-3500 3625);
DOT 1 (-3500 3725);
DOT 1 (-3500 3775);
DOT 1 (-3500 3825);
DOT 1 (-3500 3925);
DOT 1 (-3500 3875);
DOT 1 (-3500 3975);
DOT 1 (-3500 4025);
DOT 1 (-3500 4075);
DOT 1 (-3500 4175);
DOT 1 (-3500 4125);
DOT 1 (-3500 4225);
DOT 1 (-3500 4275);
DOT 1 (-3500 4325);
DOT 1 (-3500 4375);
DOT 1 (-3500 4425);
DOT 1 (-3500 4475);
DOT 1 (-3500 4525);
DOT 1 (-3500 4575);
DOT 1 (-3500 4625);
DOT 1 (-3500 4675);
DOT 1 (-3500 4725);
DOT 1 (-3500 4775);
DOT 1 (-3500 4825);
DOT 1 (-3500 4875);
DOT 1 (-3500 4925);
DOT 1 (-3500 4975);
DOT 1 (-3500 5025);
DOT 1 (-3500 5075);
DOT 1 (-3500 5125);
DOT 1 (-3500 5175);
DOT 1 (-3500 5225);
DOT 1 (-3500 5275);
DOT 1 (-3500 5325);
DOT 1 (-3500 5375);
DOT 1 (-3500 5475);
DOT 1 (-3500 5425);
DOT 1 (-3500 5525);
DOT 1 (-3500 5575);
DOT 1 (-3500 5625);
DOT 1 (-3500 5725);
DOT 1 (-3500 5675);
DOT 1 (-3500 5775);
DOT 1 (-3500 5825);
DOT 1 (-3500 5875);
DOT 1 (-3500 5925);
DOT 1 (-3500 5975);
DOT 1 (-3500 6025);
DOT 1 (-3300 5925);
DOT 1 (-3300 5975);
DOT 1 (-5275 3000);
DOT 1 (-7250 4375);
DOT 1 (-6900 4300);
DOT 1 (-5275 5900);
DOT 1 (-5275 5850);
DOT 1 (-5275 5800);
DOT 1 (-5275 5750);
DOT 1 (-5275 4900);
DOT 1 (-5275 6150);
DOT 1 (-5275 4400);
DOT 1 (-8900 625);
DOT 1 (-8900 675);
DOT 1 (-8900 725);
DOT 1 (-8900 775);
DOT 1 (-8900 825);
DOT 1 (-8900 875);
DOT 1 (-8900 925);
DOT 1 (-8900 975);
DOT 1 (-8900 1025);
DOT 1 (-8900 1075);
DOT 1 (-8900 1125);
DOT 1 (-8900 1175);
DOT 1 (-8900 1225);
DOT 1 (-8900 1275);
DOT 1 (-8900 1325);
DOT 1 (-8900 1375);
DOT 1 (-8900 1425);
DOT 1 (-8900 1475);
DOT 1 (-8900 1525);
DOT 1 (-8900 1575);
DOT 1 (-8900 1625);
DOT 1 (-8900 1675);
DOT 1 (-8900 1725);
DOT 1 (-8900 1775);
DOT 1 (-8900 1825);
DOT 1 (-8900 1875);
DOT 1 (-8900 1925);
DOT 1 (-8900 1975);
DOT 1 (-8900 2025);
DOT 1 (-8900 2075);
DOT 1 (-8900 2125);
DOT 1 (-8900 2175);
DOT 1 (-8900 2225);
DOT 1 (-8900 2275);
DOT 1 (-8900 2325);
DOT 1 (-8900 2375);
DOT 1 (-8900 2425);
DOT 1 (-8900 2475);
DOT 1 (-8900 2525);
DOT 1 (-8900 2575);
DOT 1 (-8900 2625);
DOT 1 (-8900 2675);
DOT 1 (-8900 2725);
DOT 1 (-8900 2775);
DOT 1 (-8900 2825);
DOT 1 (-8900 2875);
DOT 1 (-8900 2925);
DOT 1 (-8900 3025);
DOT 1 (-8900 2975);
DOT 1 (-8900 3075);
DOT 1 (-8900 3125);
DOT 1 (-8900 3175);
DOT 1 (-8900 3225);
DOT 1 (-8900 3275);
DOT 1 (-8900 3325);
DOT 1 (-8900 3375);
DOT 1 (-8900 3425);
DOT 1 (-8900 3475);
DOT 1 (-8900 3525);
DOT 1 (-8900 3575);
DOT 1 (-8900 3625);
DOT 1 (-8900 3675);
DOT 1 (-8900 3725);
DOT 1 (-8900 3775);
DOT 1 (-8900 3825);
DOT 1 (-8900 3875);
DOT 1 (-8900 3925);
DOT 1 (-8900 3975);
DOT 1 (-8900 4075);
DOT 1 (-8900 4125);
DOT 1 (-8900 4175);
DOT 1 (-8900 4225);
DOT 1 (-8900 4275);
DOT 1 (-8900 4325);
DOT 1 (-8900 4475);
DOT 1 (-8900 4375);
DOT 1 (-8900 4425);
DOT 1 (-8900 4525);
DOT 1 (-8900 4575);
DOT 1 (-8900 4625);
DOT 1 (-8900 4675);
DOT 1 (-8900 4725);
DOT 1 (-8900 4775);
DOT 1 (-8900 4825);
DOT 1 (-8900 4875);
DOT 1 (-8900 4925);
DOT 1 (-8900 4975);
DOT 1 (-8900 5075);
DOT 1 (-8900 5025);
DOT 1 (-8900 5125);
DOT 1 (-8900 5175);
DOT 1 (-8900 5225);
DOT 1 (-8900 5275);
DOT 1 (-8900 5325);
DOT 1 (-8900 5375);
DOT 1 (-8900 5425);
DOT 1 (-8900 5475);
DOT 1 (-8900 5525);
DOT 1 (-8900 5575);
DOT 1 (-8900 5625);
DOT 1 (-8900 5675);
DOT 1 (-8900 5725);
DOT 1 (-8900 5825);
DOT 1 (-8900 5875);
DOT 1 (-8900 5925);
DOT 1 (-8900 5975);
DOT 1 (-8900 6025);
DOT 1 (-8900 6075);
DOT 1 (-8900 6125);
DOT 1 (-8900 6175);
DOT 1 (-8900 6225);
DOT 1 (-8900 6275);
DOT 1 (-8900 6325);
DOT 1 (-7250 575);
DOT 1 (-7250 625);
DOT 1 (-7250 675);
DOT 1 (-7250 725);
DOT 1 (-7250 775);
DOT 1 (-7250 825);
DOT 1 (-7250 875);
DOT 1 (-7250 975);
DOT 1 (-7250 925);
DOT 1 (-7250 1025);
DOT 1 (-7250 1075);
DOT 1 (-7250 1125);
DOT 1 (-7250 1175);
DOT 1 (-7250 1225);
DOT 1 (-7250 1275);
DOT 1 (-7250 1325);
DOT 1 (-7250 1375);
DOT 1 (-7250 1425);
DOT 1 (-7250 1475);
DOT 1 (-7250 1525);
DOT 1 (-7250 1625);
DOT 1 (-7250 1575);
DOT 1 (-7250 1675);
DOT 1 (-7250 1725);
DOT 1 (-7250 1775);
DOT 1 (-7250 1825);
DOT 1 (-7250 1875);
DOT 1 (-7250 1925);
DOT 1 (-7250 1975);
DOT 1 (-7250 2025);
DOT 1 (-6900 950);
DOT 1 (-6900 1000);
DOT 1 (-6900 900);
DOT 1 (-6900 750);
DOT 1 (-6900 800);
DOT 1 (-6900 850);
DOT 1 (-6900 1450);
DOT 1 (-6900 1500);
DOT 1 (-6900 1300);
DOT 1 (-6900 1350);
DOT 1 (-6900 1400);
DOT 1 (-6900 1200);
DOT 1 (-6900 1250);
DOT 1 (-6900 1050);
DOT 1 (-6900 1100);
DOT 1 (-6900 1150);
DOT 1 (-6900 1950);
DOT 1 (-6900 2000);
DOT 1 (-6900 1850);
DOT 1 (-6900 1900);
DOT 1 (-6900 1800);
DOT 1 (-6900 1700);
DOT 1 (-6900 1750);
DOT 1 (-6900 1600);
DOT 1 (-6900 1650);
DOT 1 (-6900 1550);
DOT 1 (-6900 2050);
DOT 1 (-7250 2075);
DOT 1 (-7250 2125);
DOT 1 (-7250 2175);
DOT 1 (-7250 2225);
DOT 1 (-7250 2275);
DOT 1 (-7250 2325);
DOT 1 (-7250 2375);
DOT 1 (-7250 2425);
DOT 1 (-7250 2475);
DOT 1 (-7250 2525);
DOT 1 (-7250 2575);
DOT 1 (-7250 2625);
DOT 1 (-7250 2675);
DOT 1 (-7250 2725);
DOT 1 (-7250 2775);
DOT 1 (-7250 2825);
DOT 1 (-7250 2875);
DOT 1 (-7250 2925);
DOT 1 (-7250 2975);
DOT 1 (-7250 3025);
DOT 1 (-7250 3075);
DOT 1 (-7250 3125);
DOT 1 (-7250 3175);
DOT 1 (-7250 3225);
DOT 1 (-7250 3275);
DOT 1 (-7250 3325);
DOT 1 (-7250 3425);
DOT 1 (-7250 3375);
DOT 1 (-7250 3475);
DOT 1 (-7250 3525);
DOT 1 (-7250 3575);
DOT 1 (-7250 3675);
DOT 1 (-7250 3625);
DOT 1 (-7250 3725);
DOT 1 (-7250 3775);
DOT 1 (-7250 3825);
DOT 1 (-7250 3925);
DOT 1 (-7250 3875);
DOT 1 (-7250 3975);
DOT 1 (-7250 4025);
DOT 1 (-7250 4075);
DOT 1 (-6900 2450);
DOT 1 (-6900 2500);
DOT 1 (-6900 2550);
DOT 1 (-6900 2350);
DOT 1 (-6900 2400);
DOT 1 (-6900 2200);
DOT 1 (-6900 2250);
DOT 1 (-6900 2300);
DOT 1 (-6900 2100);
DOT 1 (-6900 2150);
DOT 1 (-6900 3000);
DOT 1 (-6900 3050);
DOT 1 (-6900 2950);
DOT 1 (-6900 2850);
DOT 1 (-6900 2900);
DOT 1 (-6900 2750);
DOT 1 (-6900 2800);
DOT 1 (-6900 2700);
DOT 1 (-6900 2600);
DOT 1 (-6900 2650);
DOT 1 (-6900 3500);
DOT 1 (-6900 3550);
DOT 1 (-6900 3350);
DOT 1 (-6900 3400);
DOT 1 (-6900 3450);
DOT 1 (-6900 3250);
DOT 1 (-6900 3300);
DOT 1 (-6900 3100);
DOT 1 (-6900 3150);
DOT 1 (-6900 3200);
DOT 1 (-6900 4000);
DOT 1 (-6900 4050);
DOT 1 (-6900 3900);
DOT 1 (-6900 3950);
DOT 1 (-6900 3850);
DOT 1 (-6900 3750);
DOT 1 (-6900 3800);
DOT 1 (-6900 3650);
DOT 1 (-6900 3700);
DOT 1 (-6900 3600);
DOT 1 (-5275 350);
DOT 1 (-5275 300);
DOT 1 (-5275 400);
DOT 1 (-5275 450);
DOT 1 (-5275 500);
DOT 1 (-5275 550);
DOT 1 (-5275 600);
DOT 1 (-5275 650);
DOT 1 (-5275 700);
DOT 1 (-5275 750);
DOT 1 (-5275 800);
DOT 1 (-5275 850);
DOT 1 (-5275 900);
DOT 1 (-5275 950);
DOT 1 (-5275 1000);
DOT 1 (-5275 1050);
DOT 1 (-5275 1100);
DOT 1 (-5275 1250);
DOT 1 (-5275 1200);
DOT 1 (-5275 1300);
DOT 1 (-5275 1350);
DOT 1 (-5275 1400);
DOT 1 (-5275 1450);
DOT 1 (-5275 1500);
DOT 1 (-5275 1600);
DOT 1 (-5275 1550);
DOT 1 (-5275 1650);
DOT 1 (-5275 1750);
DOT 1 (-5275 1700);
DOT 1 (-5275 1800);
DOT 1 (-5275 1850);
DOT 1 (-5275 1900);
DOT 1 (-5275 1950);
DOT 1 (-5275 2000);
DOT 1 (-5275 2050);
DOT 1 (-5275 2100);
DOT 1 (-5275 2150);
DOT 1 (-5275 2200);
DOT 1 (-5275 2250);
DOT 1 (-5275 2300);
DOT 1 (-5275 2350);
DOT 1 (-5275 2400);
DOT 1 (-5275 2450);
DOT 1 (-5275 2500);
DOT 1 (-5275 2550);
DOT 1 (-5275 2600);
DOT 1 (-5275 2650);
DOT 1 (-5275 2700);
DOT 1 (-5275 2750);
DOT 1 (-5275 2800);
DOT 1 (-5275 2850);
DOT 1 (-5275 2900);
DOT 1 (-5275 2950);
DOT 1 (-5275 3050);
DOT 1 (-5275 3200);
DOT 1 (-5275 3150);
DOT 1 (-5275 3100);
DOT 1 (-5275 3300);
DOT 1 (-5275 3250);
DOT 1 (-5275 3350);
DOT 1 (-5275 3400);
DOT 1 (-5275 3450);
DOT 1 (-5275 3500);
DOT 1 (-5275 3550);
DOT 1 (-5275 3600);
DOT 1 (-5275 3650);
DOT 1 (-5275 3700);
DOT 1 (-5275 3800);
DOT 1 (-5275 3750);
DOT 1 (-5275 3850);
DOT 1 (-5275 3900);
DOT 1 (-5275 4050);
DOT 1 (-5275 4100);
DOT 1 (-6900 4100);
DOT 1 (-7250 4125);
DOT 1 (-7250 4175);
DOT 1 (-7250 4225);
DOT 1 (-7250 4275);
DOT 1 (-7250 4325);
DOT 1 (-7250 4425);
DOT 1 (-7250 4475);
DOT 1 (-7250 4525);
DOT 1 (-7250 4575);
DOT 1 (-7250 4625);
DOT 1 (-7250 4675);
DOT 1 (-7250 4725);
DOT 1 (-7250 4775);
DOT 1 (-7250 4925);
DOT 1 (-7250 4975);
DOT 1 (-7250 5025);
DOT 1 (-7250 5075);
DOT 1 (-7250 5125);
DOT 1 (-7250 5175);
DOT 1 (-7250 5225);
DOT 1 (-7250 5275);
DOT 1 (-7250 5325);
DOT 1 (-7250 5375);
DOT 1 (-7250 5425);
DOT 1 (-7250 5475);
DOT 1 (-7250 5525);
DOT 1 (-7250 5575);
DOT 1 (-7250 5625);
DOT 1 (-7250 5725);
DOT 1 (-7250 5675);
DOT 1 (-7250 5775);
DOT 1 (-7250 5825);
DOT 1 (-7250 5875);
DOT 1 (-7250 5975);
DOT 1 (-7250 5925);
DOT 1 (-7250 6025);
DOT 1 (-7250 6075);
DOT 1 (-7250 6125);
DOT 1 (-6900 4500);
DOT 1 (-6900 4550);
DOT 1 (-6900 4600);
DOT 1 (-6900 4400);
DOT 1 (-6900 4450);
DOT 1 (-6900 4250);
DOT 1 (-6900 4350);
DOT 1 (-6900 4150);
DOT 1 (-6900 5050);
DOT 1 (-6900 5100);
DOT 1 (-6900 5000);
DOT 1 (-6900 4900);
DOT 1 (-6900 4950);
DOT 1 (-6900 4800);
DOT 1 (-6900 4850);
DOT 1 (-6900 4750);
DOT 1 (-6900 4650);
DOT 1 (-6900 4700);
DOT 1 (-6900 5550);
DOT 1 (-6900 5600);
DOT 1 (-6900 5400);
DOT 1 (-6900 5450);
DOT 1 (-6900 5500);
DOT 1 (-6900 5300);
DOT 1 (-6900 5350);
DOT 1 (-6900 5150);
DOT 1 (-6900 5200);
DOT 1 (-6900 5250);
DOT 1 (-6900 6050);
DOT 1 (-6900 6100);
DOT 1 (-6900 5950);
DOT 1 (-6900 6000);
DOT 1 (-6900 5900);
DOT 1 (-6900 5800);
DOT 1 (-6900 5850);
DOT 1 (-6900 5650);
DOT 1 (-6900 5700);
DOT 1 (-6900 5750);
DOT 1 (-7250 6175);
DOT 1 (-7250 6225);
DOT 1 (-7250 6275);
DOT 1 (-7250 6325);
DOT 1 (-5275 4200);
DOT 1 (-5275 4250);
DOT 1 (-5275 4300);
DOT 1 (-5275 4350);
DOT 1 (-5275 4450);
DOT 1 (-5275 4500);
DOT 1 (-5275 4550);
DOT 1 (-5275 4600);
DOT 1 (-5275 4650);
DOT 1 (-5275 4700);
DOT 1 (-5275 4800);
DOT 1 (-5275 4750);
DOT 1 (-5275 4850);
DOT 1 (-5275 4950);
DOT 1 (-5275 5000);
DOT 1 (-5275 5050);
DOT 1 (-5275 5100);
DOT 1 (-5275 5200);
DOT 1 (-5275 5150);
DOT 1 (-5275 5250);
DOT 1 (-5275 5300);
DOT 1 (-5275 5350);
DOT 1 (-5275 5400);
DOT 1 (-5275 5450);
DOT 1 (-5275 5500);
DOT 1 (-5275 5550);
DOT 1 (-5275 5600);
DOT 1 (-5275 5650);
DOT 1 (-5275 5700);
DOT 1 (-5275 5950);
DOT 1 (-5275 6000);
DOT 1 (-5275 6050);
DOT 1 (-5275 6100);
DOT 1 (-5275 6200);
DOT 1 (-5275 6250);
DOT 1 (-5275 6350);
DOT 1 (-3475 925);
DOT 1 (-3475 1525);
DOT 1 (-3475 1575);
DOT 1 (-3475 1625);
DOT 1 (-3475 1775);
DOT 1 (-3475 1875);
DOT 1 (-3475 1825);
DOT 1 (-3475 1925);
DOT 1 (-3475 1975);
DOT 1 (-3475 2025);
DOT 1 (-3475 2075);
DOT 1 (-3475 2125);
DOT 1 (-3475 2175);
DOT 1 (-3475 2275);
DOT 1 (-3475 2225);
DOT 1 (-3475 2325);
DOT 1 (-3475 2375);
DOT 1 (-3475 2425);
DOT 1 (-3475 2475);
DOT 1 (-3475 2525);
DOT 1 (-3300 2825);
DOT 1 (-3300 2875);
DOT 1 (-3300 2925);
DOT 1 (-3300 3025);
DOT 1 (-3300 2975);
DOT 1 (-3300 3075);
DOT 1 (-3300 3125);
DOT 1 (-3300 3175);
DOT 1 (-3300 3225);
DOT 1 (-3300 3275);
DOT 1 (-3300 3325);
DOT 1 (-3300 3375);
DOT 1 (-3300 3425);
DOT 1 (-3300 3475);
DOT 1 (-3300 3525);
DOT 1 (-3300 3575);
DOT 1 (-3300 3675);
DOT 1 (-3300 3625);
DOT 1 (-3300 3725);
DOT 1 (-3300 3775);
DOT 1 (-3300 3825);
DOT 1 (-3300 3875);
DOT 1 (-3300 3925);
DOT 1 (-3300 3975);
DOT 1 (-3300 4025);
DOT 1 (-3300 4075);
DOT 1 (-1675 875);
DOT 1 (-1675 925);
DOT 1 (-1675 975);
DOT 1 (-1675 1025);
DOT 1 (-1675 1075);
DOT 1 (-1675 1125);
DOT 1 (-1675 1175);
DOT 1 (-1675 1225);
DOT 1 (-1675 1275);
DOT 1 (-1675 1375);
DOT 1 (-1675 1325);
DOT 1 (-1675 1425);
DOT 1 (-1675 1475);
DOT 1 (-1675 1525);
DOT 1 (-1675 1625);
DOT 1 (-1675 1575);
DOT 1 (-1675 1675);
DOT 1 (-1675 1775);
DOT 1 (-1675 1725);
DOT 1 (-1675 1875);
DOT 1 (-1675 1825);
DOT 1 (-1675 1925);
DOT 1 (-1675 1975);
DOT 1 (-1675 2025);
DOT 1 (-1675 2175);
DOT 1 (-1675 2125);
DOT 1 (-1675 2075);
DOT 1 (-1675 2225);
DOT 1 (-1675 2275);
DOT 1 (-1675 2375);
DOT 1 (-1675 2425);
DOT 1 (-1675 2325);
DOT 1 (-1675 2475);
DOT 1 (-1675 2525);
DOT 1 (-1675 2675);
DOT 1 (-1675 2625);
DOT 1 (-1675 2575);
DOT 1 (-1675 2725);
DOT 1 (-1675 2775);
DOT 1 (-1675 2825);
DOT 1 (-1675 2925);
DOT 1 (-1675 2875);
DOT 1 (-1675 2975);
DOT 1 (-1675 3025);
DOT 1 (-1675 3075);
DOT 1 (-1675 3125);
DOT 1 (-1675 3175);
DOT 1 (-1675 3225);
DOT 1 (-1675 3325);
DOT 1 (-1675 3275);
DOT 1 (-1675 3425);
DOT 1 (-1675 3375);
DOT 1 (-1675 3475);
DOT 1 (-1675 3525);
DOT 1 (-1675 3575);
DOT 1 (-1675 3625);
DOT 1 (-1675 3675);
DOT 1 (-1675 3725);
DOT 1 (-1675 3775);
DOT 1 (-1675 3825);
DOT 1 (-1675 3925);
DOT 1 (-1675 3875);
DOT 1 (-1675 3975);
DOT 1 (-1675 4025);
DOT 1 (-1675 4075);
DOT 1 (-3300 4125);
DOT 1 (-3300 4175);
DOT 1 (-3300 4225);
DOT 1 (-3300 4275);
DOT 1 (-3300 4325);
DOT 1 (-3300 4375);
DOT 1 (-3300 4425);
DOT 1 (-3300 4475);
DOT 1 (-3300 4525);
DOT 1 (-3300 4575);
DOT 1 (-3300 4625);
DOT 1 (-3300 4675);
DOT 1 (-3300 4725);
DOT 1 (-3300 4825);
DOT 1 (-3300 4775);
DOT 1 (-3300 4875);
DOT 1 (-3300 4925);
DOT 1 (-3300 4975);
DOT 1 (-3300 5025);
DOT 1 (-3300 5075);
DOT 1 (-3300 5125);
DOT 1 (-3300 5175);
DOT 1 (-3300 5225);
DOT 1 (-3300 5275);
DOT 1 (-3300 5325);
DOT 1 (-3300 5375);
DOT 1 (-3300 5475);
DOT 1 (-3300 5425);
DOT 1 (-3300 5525);
DOT 1 (-3300 5575);
DOT 1 (-3300 5625);
DOT 1 (-3300 5725);
DOT 1 (-3300 5675);
DOT 1 (-3300 5775);
DOT 1 (-3300 5825);
DOT 1 (-3300 5875);
DOT 1 (-3300 6025);
DOT 1 (-3300 6075);
DOT 1 (-3300 6125);
DOT 1 (-3300 6175);
DOT 1 (-3300 6225);
DOT 1 (-3300 6275);
DOT 1 (-3300 6325);
DOT 1 (-3300 6375);
DOT 1 (-3300 6425);
DOT 1 (-3300 6475);
DOT 1 (-3300 6525);
DOT 1 (-1675 4125);
DOT 1 (-1675 4175);
DOT 1 (-1675 4225);
DOT 1 (-1675 4275);
DOT 1 (-1675 4325);
DOT 1 (-1675 4425);
DOT 1 (-1675 4475);
DOT 1 (-1675 4375);
DOT 1 (-1675 4525);
DOT 1 (-1675 4575);
DOT 1 (-1675 4725);
DOT 1 (-1675 4675);
DOT 1 (-1675 4625);
DOT 1 (-1675 4775);
DOT 1 (-1675 4825);
DOT 1 (-1675 4875);
DOT 1 (-1675 4975);
DOT 1 (-1675 4925);
DOT 1 (-1675 5025);
DOT 1 (-1675 5075);
DOT 1 (-1675 5125);
DOT 1 (-1675 5175);
DOT 1 (-1675 5225);
DOT 1 (-1675 5275);
DOT 1 (-1675 5375);
DOT 1 (-1675 5325);
DOT 1 (-1675 5475);
DOT 1 (-1675 5425);
DOT 1 (-1675 5525);
DOT 1 (-1675 5575);
DOT 1 (-1675 5625);
DOT 1 (-1675 5725);
DOT 1 (-1675 5675);
DOT 1 (-1675 5775);
DOT 1 (-1675 5825);
DOT 1 (-1675 5875);
DOT 1 (-1675 5975);
DOT 1 (-1675 5925);
DOT 1 (-1675 6025);
DOT 1 (-1675 6075);
DOT 1 (-1675 6125);
DOT 1 (-1675 6225);
DOT 1 (-1675 6175);
DOT 1 (-1675 6275);
DOT 1 (-1675 6375);
DOT 1 (-1675 6325);
DOT 1 (-1675 6425);
DOT 1 (-1675 6475);
DOT 1 (-8900 5775);
DOT 1 (-5275 6300);
DOT 1 (-5275 4000);
DOT 1 (-5275 3950);
DOT 1 (-5275 4150);
DOT 1 (-8900 4025);
DOT 1 (-3300 2775);
DOT 1 (-3475 2625);
DOT 1 (-3475 1725);
DOT 1 (-3475 1675);
QUIT
